FILE_TYPE = MACRO_DRAWING;
SET COLOR_WIRE YELLOW;
SET COLOR_PROP ORANGE;
SET COLOR_DOT WHITE;
SET COLOR_ARC YELLOW;
SET COLOR_BODY GREEN;
SET COLOR_NOTE PURPLE;
SET PROP_DISPLAY VALUE;
SET PAGE_NUMBER P470;
FORCEADD OFFPAGE..1
(-8775 3450);
FORCEPROP 2 LAST $XR0 80 
J 0
(-8996 3450);
DISPLAY 0.638298 (-8996 3450);
PAINT MONO (-8996 3450);
FORCEPROP 2 LAST CDS_LIB standard
J 0
(-8775 3450);
DISPLAY INVISIBLE (-8775 3450);
FORCEPROP 1 LAST OFFPAGE TRUE
J 0
(-8450 3325);
DISPLAY 0.872340 (-8450 3325);
PAINT GREEN (-8450 3325);
DISPLAY INVISIBLE (-8450 3325);
FORCEPROP 1 LAST COMMENT_BODY TRUE
J 0
(-8650 3350);
DISPLAY 0.872340 (-8650 3350);
PAINT GREEN (-8650 3350);
DISPLAY INVISIBLE (-8650 3350);
FORCEPROP 2 LAST PATH I1
J 0
(-8725 3525);
DISPLAY 0.680851 (-8725 3525);
DISPLAY INVISIBLE (-8725 3525);
FORCEADD UNIVERSAL_GND..1
(-7975 2800);
FORCEPROP 3 LASTPIN (-7975 2850) SIG_NAME GND\g
J 0
(-7965 2860);
DISPLAY 0.659574 (-7965 2860);
PAINT MONO (-7965 2860);
DISPLAY INVISIBLE (-7965 2860);
FORCEPROP 2 LAST CDS_LIB pure_quanta_power
J 0
(-7975 2800);
DISPLAY INVISIBLE (-7975 2800);
FORCEPROP 1 LAST HDL_POWER GND
J 1
(-7950 2725);
DISPLAY 0.872340 (-7950 2725);
PAINT GREEN (-7950 2725);
DISPLAY INVISIBLE (-7950 2725);
FORCEPROP 1 LAST PATH I10
J 0
(-7900 2800);
DISPLAY 0.872340 (-7900 2800);
PAINT AQUA (-7900 2800);
DISPLAY INVISIBLE (-7900 2800);
FORCEADD UNIVERSAL_GND..1
(-7500 2200);
FORCEPROP 3 LASTPIN (-7500 2250) SIG_NAME GND\g
J 0
(-7490 2260);
DISPLAY 0.659574 (-7490 2260);
PAINT MONO (-7490 2260);
DISPLAY INVISIBLE (-7490 2260);
FORCEPROP 2 LAST CDS_LIB pure_quanta_power
J 0
(-7500 2200);
DISPLAY INVISIBLE (-7500 2200);
FORCEPROP 1 LAST HDL_POWER GND
J 1
(-7475 2125);
DISPLAY 0.872340 (-7475 2125);
PAINT GREEN (-7475 2125);
DISPLAY INVISIBLE (-7475 2125);
FORCEPROP 1 LAST PATH I11
J 0
(-7425 2200);
DISPLAY 0.872340 (-7425 2200);
PAINT AQUA (-7425 2200);
DISPLAY INVISIBLE (-7425 2200);
FORCEADD Q_CAP..1
R 2
(-7500 2425);
FORCEPROP 1 LAST LOCATION PC6525
J 0
(-7450 2565);
DISPLAY 0.489362 (-7450 2565);
PAINT SKYBLUE (-7450 2565);
FORCEPROP 2 LAST SEC 1
J 0
(-7550 2621);
DISPLAY 0.680851 (-7550 2621);
PAINT MONO (-7550 2621);
DISPLAY INVISIBLE (-7550 2621);
FORCEPROP 1 LASTPIN (-7500 2525) $PN 1
J 2
(-7454 2496);
DISPLAY 0.489362 (-7454 2496);
FORCEPROP 1 LASTPIN (-7500 2325) $PN 2
J 2
(-7456 2320);
DISPLAY 0.489362 (-7456 2320);
FORCEPROP 1 LAST VALUE 1UF
J 0
(-7450 2503);
DISPLAY 0.489362 (-7450 2503);
PAINT SKYBLUE (-7450 2503);
FORCEPROP 1 LAST PACK_TYPE C0402
J 0
(-7450 2307);
DISPLAY 0.489362 (-7450 2307);
PAINT SKYBLUE (-7450 2307);
FORCEPROP 1 LAST MATERIAL X6S
J 0
(-7450 2356);
DISPLAY 0.489362 (-7450 2356);
PAINT SKYBLUE (-7450 2356);
FORCEPROP 1 LAST TOLERANCE 10%
J 0
(-7450 2405);
DISPLAY 0.489362 (-7450 2405);
PAINT SKYBLUE (-7450 2405);
FORCEPROP 1 LAST VOLTAGE 25V
J 0
(-7450 2454);
DISPLAY 0.489362 (-7450 2454);
PAINT SKYBLUE (-7450 2454);
FORCEPROP 2 LAST CDS_LIB pure_quanta
J 0
(-7500 2425);
DISPLAY INVISIBLE (-7500 2425);
FORCEPROP 2 LAST SIGNAL_MODEL DEFAULT_CAPACITOR_100000PF_2_1
R 3
J 1
(-7570 2373);
DISPLAY 0.744681 (-7570 2373);
PAINT MONO (-7570 2373);
DISPLAY INVISIBLE (-7570 2373);
FORCEPROP 2 LAST SEC_TYPE C0402
J 0
(-7550 2621);
DISPLAY 1.021277 (-7550 2621);
DISPLAY INVISIBLE (-7550 2621);
FORCEPROP 1 LAST PATH I12
J 2
(-7550 2575);
DISPLAY 0.978723 (-7550 2575);
PAINT WHITE (-7550 2575);
DISPLAY INVISIBLE (-7550 2575);
FORCEPROP 1 LAST PART_NUMBER CH5104KEB02
J 0
(-7450 2258);
DISPLAY 0.489362 (-7450 2258);
PAINT SKYBLUE (-7450 2258);
DISPLAY INVISIBLE (-7450 2258);
FORCEADD Q_RES..2
(-7500 2850);
FORCEPROP 1 LAST LOCATION PR6521
J 0
(-7455 2975);
DISPLAY 0.489362 (-7455 2975);
PAINT SKYBLUE (-7455 2975);
FORCEPROP 0 LAST $SEC 1
J 0
(-7450 3025);
DISPLAY 0.680851 (-7450 3025);
PAINT MONO (-7450 3025);
DISPLAY INVISIBLE (-7450 3025);
FORCEPROP 0 LAST CDS_SEC 1
J 0
(-7450 3025);
DISPLAY 1.021277 (-7450 3025);
DISPLAY INVISIBLE (-7450 3025);
FORCEPROP 1 LASTPIN (-7500 2950) $PN 1
J 0
(-7495 2912);
DISPLAY 0.489362 (-7495 2912);
PAINT MONO (-7495 2912);
FORCEPROP 1 LASTPIN (-7500 2750) $PN 2
J 0
(-7495 2760);
DISPLAY 0.489362 (-7495 2760);
PAINT MONO (-7495 2760);
FORCEPROP 1 LAST MATERIAL CHIP
J 0
(-7460 2775);
DISPLAY 0.489362 (-7460 2775);
PAINT SKYBLUE (-7460 2775);
FORCEPROP 1 LAST VALUE 0
J 0
(-7455 2925);
DISPLAY 0.489362 (-7455 2925);
PAINT SKYBLUE (-7455 2925);
FORCEPROP 1 LAST TOLERANCE 5%
J 0
(-7455 2875);
DISPLAY 0.489362 (-7455 2875);
PAINT SKYBLUE (-7455 2875);
FORCEPROP 1 LAST WATTAGE 1/16W
J 0
(-7460 2825);
DISPLAY 0.489362 (-7460 2825);
PAINT SKYBLUE (-7460 2825);
FORCEPROP 1 LAST PACK_TYPE 0402LF
J 0
(-7460 2675);
DISPLAY 0.489362 (-7460 2675);
PAINT SKYBLUE (-7460 2675);
FORCEPROP 2 LAST CDS_LIB pure_quanta
J 0
(-7500 2850);
DISPLAY INVISIBLE (-7500 2850);
FORCEPROP 1 LAST PATH I13
J 0
(-7450 3025);
DISPLAY 0.978723 (-7450 3025);
PAINT WHITE (-7450 3025);
DISPLAY INVISIBLE (-7450 3025);
FORCEPROP 1 LAST PART_NUMBER CS00002JB13
J 0
(-7460 2725);
DISPLAY 0.489362 (-7460 2725);
PAINT SKYBLUE (-7460 2725);
DISPLAY INVISIBLE (-7460 2725);
FORCEADD UNIVERSAL_POWER..1
(-7500 3050);
FORCEPROP 3 LASTPIN (-7500 3000) SIG_NAME P3V3_AUX\g
J 0
(-7490 3010);
DISPLAY 0.659574 (-7490 3010);
PAINT MONO (-7490 3010);
DISPLAY INVISIBLE (-7490 3010);
FORCEPROP 1 LAST HDL_POWER P3V3_AUX
J 1
(-7500 3100);
DISPLAY 0.489362 (-7500 3100);
PAINT GREEN (-7500 3100);
FORCEPROP 2 LAST CDS_LIB mstr_symbols
J 0
(-7500 3050);
PAINT MONO (-7500 3050);
DISPLAY INVISIBLE (-7500 3050);
FORCEPROP 1 LAST PATH I14
J 0
(-7450 3075);
DISPLAY 0.872340 (-7450 3075);
PAINT AQUA (-7450 3075);
DISPLAY INVISIBLE (-7450 3075);
FORCEADD UNIVERSAL_GND..1
(-7875 3625);
FORCEPROP 3 LASTPIN (-7875 3675) SIG_NAME GND\g
J 0
(-7865 3685);
DISPLAY 0.659574 (-7865 3685);
PAINT MONO (-7865 3685);
DISPLAY INVISIBLE (-7865 3685);
FORCEPROP 2 LAST CDS_LIB pure_quanta_power
J 0
(-7875 3625);
DISPLAY INVISIBLE (-7875 3625);
FORCEPROP 1 LAST HDL_POWER GND
J 1
(-7850 3550);
DISPLAY 0.872340 (-7850 3550);
PAINT GREEN (-7850 3550);
DISPLAY INVISIBLE (-7850 3550);
FORCEPROP 1 LAST PATH I15
J 0
(-7800 3625);
DISPLAY 0.872340 (-7800 3625);
PAINT AQUA (-7800 3625);
DISPLAY INVISIBLE (-7800 3625);
FORCEADD Q_CAP..1
(-8075 4000);
FORCEPROP 1 LAST LOCATION PC6520
J 0
(-8025 4100);
DISPLAY 0.489362 (-8025 4100);
PAINT SKYBLUE (-8025 4100);
FORCEPROP 0 LAST $SEC 1
J 0
(-8025 4125);
DISPLAY 0.680851 (-8025 4125);
PAINT MONO (-8025 4125);
DISPLAY INVISIBLE (-8025 4125);
FORCEPROP 0 LAST CDS_SEC 1
J 0
(-8025 4125);
DISPLAY 1.021277 (-8025 4125);
DISPLAY INVISIBLE (-8025 4125);
FORCEPROP 1 LASTPIN (-8075 4100) $PN 1
J 0
(-8065 4080);
DISPLAY 0.489362 (-8065 4080);
PAINT MONO (-8065 4080);
FORCEPROP 1 LASTPIN (-8075 3900) $PN 2
J 0
(-8065 3880);
DISPLAY 0.489362 (-8065 3880);
PAINT MONO (-8065 3880);
FORCEPROP 1 LAST PACK_TYPE C0805
J 0
(-8025 3800);
DISPLAY 0.489362 (-8025 3800);
PAINT SKYBLUE (-8025 3800);
FORCEPROP 1 LAST VALUE 22UF
J 0
(-8025 4050);
DISPLAY 0.489362 (-8025 4050);
PAINT SKYBLUE (-8025 4050);
FORCEPROP 1 LAST MATERIAL X6S
J 0
(-8025 3900);
DISPLAY 0.489362 (-8025 3900);
PAINT SKYBLUE (-8025 3900);
FORCEPROP 1 LAST VOLTAGE 16V
J 0
(-8025 4000);
DISPLAY 0.489362 (-8025 4000);
PAINT SKYBLUE (-8025 4000);
FORCEPROP 1 LAST TOLERANCE 20%
J 0
(-8025 3950);
DISPLAY 0.489362 (-8025 3950);
PAINT SKYBLUE (-8025 3950);
FORCEPROP 2 LAST CDS_LIB pure_quanta
J 0
(-8075 4000);
DISPLAY INVISIBLE (-8075 4000);
FORCEPROP 1 LAST PATH I16
J 0
(-8025 4150);
DISPLAY 0.978723 (-8025 4150);
PAINT WHITE (-8025 4150);
DISPLAY INVISIBLE (-8025 4150);
FORCEPROP 1 LAST PART_NUMBER CH6223MEA01
J 0
(-8025 3850);
DISPLAY 0.489362 (-8025 3850);
PAINT SKYBLUE (-8025 3850);
DISPLAY INVISIBLE (-8025 3850);
FORCEADD Q_CAP..1
(-7850 4000);
FORCEPROP 1 LAST LOCATION PC6521
J 0
(-7800 4100);
DISPLAY 0.489362 (-7800 4100);
PAINT SKYBLUE (-7800 4100);
FORCEPROP 0 LAST $SEC 1
J 0
(-7800 4125);
DISPLAY 0.680851 (-7800 4125);
PAINT MONO (-7800 4125);
DISPLAY INVISIBLE (-7800 4125);
FORCEPROP 0 LAST CDS_SEC 1
J 0
(-7800 4150);
DISPLAY 1.021277 (-7800 4150);
DISPLAY INVISIBLE (-7800 4150);
FORCEPROP 1 LASTPIN (-7850 4100) $PN 1
J 0
(-7840 4080);
DISPLAY 0.489362 (-7840 4080);
PAINT MONO (-7840 4080);
FORCEPROP 1 LASTPIN (-7850 3900) $PN 2
J 0
(-7840 3880);
DISPLAY 0.489362 (-7840 3880);
PAINT MONO (-7840 3880);
FORCEPROP 1 LAST TOLERANCE 20%
J 0
(-7800 3950);
DISPLAY 0.489362 (-7800 3950);
PAINT SKYBLUE (-7800 3950);
FORCEPROP 1 LAST VOLTAGE 16V
J 0
(-7800 4000);
DISPLAY 0.489362 (-7800 4000);
PAINT SKYBLUE (-7800 4000);
FORCEPROP 1 LAST VALUE 22UF
J 0
(-7800 4050);
DISPLAY 0.489362 (-7800 4050);
PAINT SKYBLUE (-7800 4050);
FORCEPROP 1 LAST MATERIAL X6S
J 0
(-7800 3900);
DISPLAY 0.489362 (-7800 3900);
PAINT SKYBLUE (-7800 3900);
FORCEPROP 1 LAST PACK_TYPE C0805
J 0
(-7800 3800);
DISPLAY 0.489362 (-7800 3800);
PAINT SKYBLUE (-7800 3800);
FORCEPROP 2 LAST CDS_LIB pure_quanta
J 0
(-7850 4000);
DISPLAY INVISIBLE (-7850 4000);
FORCEPROP 1 LAST PATH I17
J 0
(-7800 4150);
DISPLAY 0.978723 (-7800 4150);
PAINT WHITE (-7800 4150);
DISPLAY INVISIBLE (-7800 4150);
FORCEPROP 1 LAST PART_NUMBER CH6223MEA01
J 0
(-7800 3850);
DISPLAY 0.489362 (-7800 3850);
PAINT SKYBLUE (-7800 3850);
DISPLAY INVISIBLE (-7800 3850);
FORCEADD Q_CAP..1
(-7675 4000);
FORCEPROP 1 LAST LOCATION PC6522
J 0
(-7625 4100);
DISPLAY 0.489362 (-7625 4100);
PAINT SKYBLUE (-7625 4100);
FORCEPROP 0 LAST $SEC 1
J 0
(-7625 4125);
DISPLAY 0.680851 (-7625 4125);
PAINT MONO (-7625 4125);
DISPLAY INVISIBLE (-7625 4125);
FORCEPROP 0 LAST CDS_SEC 1
J 0
(-7625 4150);
DISPLAY 1.021277 (-7625 4150);
DISPLAY INVISIBLE (-7625 4150);
FORCEPROP 1 LASTPIN (-7675 4100) $PN 1
J 0
(-7665 4080);
DISPLAY 0.489362 (-7665 4080);
PAINT MONO (-7665 4080);
FORCEPROP 1 LASTPIN (-7675 3900) $PN 2
J 0
(-7665 3880);
DISPLAY 0.489362 (-7665 3880);
PAINT MONO (-7665 3880);
FORCEPROP 1 LAST TOLERANCE 20%
J 0
(-7625 3950);
DISPLAY 0.489362 (-7625 3950);
PAINT SKYBLUE (-7625 3950);
FORCEPROP 1 LAST VALUE 22UF
J 0
(-7625 4050);
DISPLAY 0.489362 (-7625 4050);
PAINT SKYBLUE (-7625 4050);
FORCEPROP 1 LAST VOLTAGE 16V
J 0
(-7625 4000);
DISPLAY 0.489362 (-7625 4000);
PAINT SKYBLUE (-7625 4000);
FORCEPROP 1 LAST PACK_TYPE C0805
J 0
(-7625 3800);
DISPLAY 0.489362 (-7625 3800);
PAINT SKYBLUE (-7625 3800);
FORCEPROP 1 LAST MATERIAL X6S
J 0
(-7625 3900);
DISPLAY 0.489362 (-7625 3900);
PAINT SKYBLUE (-7625 3900);
FORCEPROP 2 LAST CDS_LIB pure_quanta
J 0
(-7675 4000);
DISPLAY INVISIBLE (-7675 4000);
FORCEPROP 1 LAST PATH I18
J 0
(-7625 4150);
DISPLAY 0.978723 (-7625 4150);
PAINT WHITE (-7625 4150);
DISPLAY INVISIBLE (-7625 4150);
FORCEPROP 1 LAST PART_NUMBER CH6223MEA01
J 0
(-7625 3850);
DISPLAY 0.489362 (-7625 3850);
PAINT SKYBLUE (-7625 3850);
DISPLAY INVISIBLE (-7625 3850);
FORCEADD UNIVERSAL_GND..1
(-6625 2175);
FORCEPROP 3 LASTPIN (-6625 2225) SIG_NAME GND\g
J 0
(-6615 2235);
DISPLAY 0.659574 (-6615 2235);
PAINT MONO (-6615 2235);
DISPLAY INVISIBLE (-6615 2235);
FORCEPROP 2 LAST CDS_LIB pure_quanta_power
J 0
(-6625 2175);
DISPLAY INVISIBLE (-6625 2175);
FORCEPROP 1 LAST HDL_POWER GND
J 1
(-6600 2100);
DISPLAY 0.872340 (-6600 2100);
PAINT GREEN (-6600 2100);
DISPLAY INVISIBLE (-6600 2100);
FORCEPROP 1 LAST PATH I19
J 0
(-6550 2175);
DISPLAY 0.872340 (-6550 2175);
PAINT AQUA (-6550 2175);
DISPLAY INVISIBLE (-6550 2175);
FORCEADD UNIVERSAL_GND..1
(-9150 3700);
FORCEPROP 3 LASTPIN (-9150 3750) SIG_NAME GND\g
J 0
(-9140 3760);
DISPLAY 0.659574 (-9140 3760);
PAINT MONO (-9140 3760);
DISPLAY INVISIBLE (-9140 3760);
FORCEPROP 2 LAST CDS_LIB pure_quanta_power
J 0
(-9150 3700);
DISPLAY INVISIBLE (-9150 3700);
FORCEPROP 1 LAST HDL_POWER GND
J 1
(-9125 3625);
DISPLAY 0.872340 (-9125 3625);
PAINT GREEN (-9125 3625);
DISPLAY INVISIBLE (-9125 3625);
FORCEPROP 1 LAST PATH I2
J 0
(-9075 3700);
DISPLAY 0.872340 (-9075 3700);
PAINT AQUA (-9075 3700);
DISPLAY INVISIBLE (-9075 3700);
FORCEADD Q_RES..2
(-6625 2425);
FORCEPROP 1 LAST LOCATION PR6522
J 0
(-6580 2550);
DISPLAY 0.489362 (-6580 2550);
PAINT SKYBLUE (-6580 2550);
FORCEPROP 2 LAST SEC 1
J 0
(-6563 2668);
DISPLAY 0.680851 (-6563 2668);
PAINT MONO (-6563 2668);
DISPLAY INVISIBLE (-6563 2668);
FORCEPROP 1 LASTPIN (-6625 2525) $PN 1
J 0
(-6620 2487);
DISPLAY 0.489362 (-6620 2487);
FORCEPROP 1 LASTPIN (-6625 2325) $PN 2
J 0
(-6620 2335);
DISPLAY 0.489362 (-6620 2335);
FORCEPROP 1 LAST VALUE 7.15K
J 0
(-6580 2500);
DISPLAY 0.489362 (-6580 2500);
PAINT SKYBLUE (-6580 2500);
FORCEPROP 1 LAST TOLERANCE 1%
J 0
(-6580 2450);
DISPLAY 0.489362 (-6580 2450);
PAINT SKYBLUE (-6580 2450);
FORCEPROP 1 LAST MATERIAL CHIP
J 0
(-6585 2350);
DISPLAY 0.489362 (-6585 2350);
PAINT SKYBLUE (-6585 2350);
FORCEPROP 1 LAST PACK_TYPE 0402LF
J 0
(-6585 2250);
DISPLAY 0.489362 (-6585 2250);
PAINT SKYBLUE (-6585 2250);
FORCEPROP 1 LAST WATTAGE 1/16W
J 0
(-6585 2400);
DISPLAY 0.489362 (-6585 2400);
PAINT SKYBLUE (-6585 2400);
FORCEPROP 2 LAST CDS_LIB pure_quanta
R 3
J 0
(-6625 2425);
DISPLAY INVISIBLE (-6625 2425);
FORCEPROP 2 LAST SEC_TYPE 0402LF
J 0
(-6563 2668);
DISPLAY 1.021277 (-6563 2668);
DISPLAY INVISIBLE (-6563 2668);
FORCEPROP 1 LAST PATH I20
J 0
(-6575 2600);
DISPLAY 0.978723 (-6575 2600);
PAINT WHITE (-6575 2600);
DISPLAY INVISIBLE (-6575 2600);
FORCEPROP 1 LAST PART_NUMBER CS27152FB03
J 0
(-6585 2300);
DISPLAY 0.489362 (-6585 2300);
PAINT SKYBLUE (-6585 2300);
DISPLAY INVISIBLE (-6585 2300);
FORCEADD Q_RES..1
(-7000 3250);
FORCEPROP 1 LAST LOCATION PR6520
J 0
(-7025 3300);
DISPLAY 0.489362 (-7025 3300);
PAINT SKYBLUE (-7025 3300);
FORCEPROP 0 LAST $SEC 1
J 0
(-7050 3325);
DISPLAY 0.680851 (-7050 3325);
PAINT MONO (-7050 3325);
DISPLAY INVISIBLE (-7050 3325);
FORCEPROP 0 LAST CDS_SEC 1
J 0
(-7050 3325);
DISPLAY 1.021277 (-7050 3325);
DISPLAY INVISIBLE (-7050 3325);
FORCEPROP 1 LASTPIN (-7100 3250) $PN 1
J 0
(-7088 3262);
DISPLAY 0.489362 (-7088 3262);
PAINT MONO (-7088 3262);
FORCEPROP 1 LASTPIN (-6900 3250) $PN 2
J 0
(-6938 3262);
DISPLAY 0.489362 (-6938 3262);
PAINT MONO (-6938 3262);
FORCEPROP 1 LAST VALUE 0
J 2
(-7175 3275);
DISPLAY 0.489362 (-7175 3275);
PAINT SKYBLUE (-7175 3275);
FORCEPROP 1 LAST MATERIAL CHIP
J 0
(-7300 3150);
DISPLAY 0.489362 (-7300 3150);
PAINT SKYBLUE (-7300 3150);
FORCEPROP 1 LAST TOLERANCE 5%
J 0
(-6875 3275);
DISPLAY 0.489362 (-6875 3275);
PAINT SKYBLUE (-6875 3275);
FORCEPROP 1 LAST PACK_TYPE 0402LF
J 0
(-6925 3175);
DISPLAY 0.489362 (-6925 3175);
PAINT SKYBLUE (-6925 3175);
FORCEPROP 1 LAST WATTAGE 1/16W
J 0
(-6925 3150);
DISPLAY 0.489362 (-6925 3150);
PAINT SKYBLUE (-6925 3150);
FORCEPROP 2 LAST CDS_LIB pure_quanta
J 0
(-7000 3250);
DISPLAY INVISIBLE (-7000 3250);
FORCEPROP 1 LAST PATH I21
J 0
(-7050 3400);
DISPLAY 0.978723 (-7050 3400);
PAINT WHITE (-7050 3400);
DISPLAY INVISIBLE (-7050 3400);
FORCEPROP 1 LAST PART_NUMBER CS00002JB13
J 0
(-7300 3175);
DISPLAY 0.489362 (-7300 3175);
PAINT SKYBLUE (-7300 3175);
DISPLAY INVISIBLE (-7300 3175);
FORCEADD Q_CAP..1
(-7450 4000);
FORCEPROP 1 LAST LOCATION PC6523
J 0
(-7400 4100);
DISPLAY 0.489362 (-7400 4100);
PAINT SKYBLUE (-7400 4100);
FORCEPROP 0 LAST $SEC 1
J 0
(-7400 4125);
DISPLAY 0.680851 (-7400 4125);
PAINT MONO (-7400 4125);
DISPLAY INVISIBLE (-7400 4125);
FORCEPROP 0 LAST CDS_SEC 1
J 0
(-7400 4150);
DISPLAY 0.680851 (-7400 4150);
DISPLAY INVISIBLE (-7400 4150);
FORCEPROP 1 LASTPIN (-7450 4100) $PN 1
J 0
(-7440 4080);
DISPLAY 0.489362 (-7440 4080);
PAINT MONO (-7440 4080);
FORCEPROP 1 LASTPIN (-7450 3900) $PN 2
J 0
(-7440 3880);
DISPLAY 0.489362 (-7440 3880);
PAINT MONO (-7440 3880);
FORCEPROP 1 LAST TOLERANCE 20%
J 0
(-7400 3950);
DISPLAY 0.489362 (-7400 3950);
PAINT SKYBLUE (-7400 3950);
FORCEPROP 1 LAST VOLTAGE 16V
J 0
(-7400 4000);
DISPLAY 0.489362 (-7400 4000);
PAINT SKYBLUE (-7400 4000);
FORCEPROP 1 LAST VALUE 22UF
J 0
(-7400 4050);
DISPLAY 0.489362 (-7400 4050);
PAINT SKYBLUE (-7400 4050);
FORCEPROP 1 LAST MATERIAL X6S
J 0
(-7400 3900);
DISPLAY 0.489362 (-7400 3900);
PAINT SKYBLUE (-7400 3900);
FORCEPROP 1 LAST PACK_TYPE C0805
J 0
(-7400 3800);
DISPLAY 0.489362 (-7400 3800);
PAINT SKYBLUE (-7400 3800);
FORCEPROP 2 LAST CDS_LIB pure_quanta
J 0
(-7450 4000);
DISPLAY INVISIBLE (-7450 4000);
FORCEPROP 1 LAST PATH I22
J 0
(-7400 4150);
DISPLAY 0.978723 (-7400 4150);
PAINT WHITE (-7400 4150);
DISPLAY INVISIBLE (-7400 4150);
FORCEPROP 1 LAST PART_NUMBER CH6223MEA01
J 0
(-7400 3850);
DISPLAY 0.489362 (-7400 3850);
PAINT SKYBLUE (-7400 3850);
DISPLAY INVISIBLE (-7400 3850);
FORCEADD Q_CAP..1
(-7250 4000);
FORCEPROP 1 LAST LOCATION PC6524
J 0
(-7200 4100);
DISPLAY 0.489362 (-7200 4100);
PAINT SKYBLUE (-7200 4100);
FORCEPROP 0 LAST $SEC 1
J 0
(-7200 4125);
DISPLAY 0.680851 (-7200 4125);
PAINT MONO (-7200 4125);
DISPLAY INVISIBLE (-7200 4125);
FORCEPROP 0 LAST CDS_SEC 1
J 0
(-7200 4125);
DISPLAY 1.021277 (-7200 4125);
DISPLAY INVISIBLE (-7200 4125);
FORCEPROP 1 LASTPIN (-7250 4100) $PN 1
J 0
(-7240 4080);
DISPLAY 0.489362 (-7240 4080);
PAINT MONO (-7240 4080);
FORCEPROP 1 LASTPIN (-7250 3900) $PN 2
J 0
(-7240 3880);
DISPLAY 0.489362 (-7240 3880);
PAINT MONO (-7240 3880);
FORCEPROP 1 LAST PACK_TYPE C0402
J 0
(-7200 3800);
DISPLAY 0.489362 (-7200 3800);
PAINT SKYBLUE (-7200 3800);
FORCEPROP 1 LAST VALUE 1UF
J 0
(-7200 4050);
DISPLAY 0.489362 (-7200 4050);
PAINT SKYBLUE (-7200 4050);
FORCEPROP 1 LAST MATERIAL X6S
J 0
(-7200 3900);
DISPLAY 0.489362 (-7200 3900);
PAINT SKYBLUE (-7200 3900);
FORCEPROP 1 LAST VOLTAGE 25V
J 0
(-7200 4000);
DISPLAY 0.489362 (-7200 4000);
PAINT SKYBLUE (-7200 4000);
FORCEPROP 1 LAST TOLERANCE 10%
J 0
(-7200 3950);
DISPLAY 0.489362 (-7200 3950);
PAINT SKYBLUE (-7200 3950);
FORCEPROP 2 LAST CDS_LIB pure_quanta
J 0
(-7250 4000);
PAINT MONO (-7250 4000);
DISPLAY INVISIBLE (-7250 4000);
FORCEPROP 1 LAST PATH I23
J 0
(-7200 4150);
DISPLAY 0.978723 (-7200 4150);
PAINT WHITE (-7200 4150);
DISPLAY INVISIBLE (-7200 4150);
FORCEPROP 1 LAST PART_NUMBER CH5104KEB02
J 0
(-7200 3850);
DISPLAY 0.489362 (-7200 3850);
PAINT SKYBLUE (-7200 3850);
DISPLAY INVISIBLE (-7200 3850);
FORCEADD UNIVERSAL_GND..1
(-5050 2325);
FORCEPROP 3 LASTPIN (-5050 2375) SIG_NAME GND\g
J 0
(-5040 2385);
DISPLAY 0.659574 (-5040 2385);
PAINT MONO (-5040 2385);
DISPLAY INVISIBLE (-5040 2385);
FORCEPROP 2 LAST CDS_LIB pure_quanta_power
J 0
(-5050 2325);
DISPLAY INVISIBLE (-5050 2325);
FORCEPROP 1 LAST HDL_POWER GND
J 1
(-5025 2250);
DISPLAY 0.872340 (-5025 2250);
PAINT GREEN (-5025 2250);
DISPLAY INVISIBLE (-5025 2250);
FORCEPROP 1 LAST PATH I24
J 0
(-4975 2325);
DISPLAY 0.872340 (-4975 2325);
PAINT AQUA (-4975 2325);
DISPLAY INVISIBLE (-4975 2325);
FORCEADD Q_CAP..1
(-4925 2575);
FORCEPROP 1 LAST LOCATION PC6537
J 0
(-4875 2650);
DISPLAY 0.489362 (-4875 2650);
PAINT SKYBLUE (-4875 2650);
FORCEPROP 0 LAST $SEC 1
J 0
(-4875 2700);
DISPLAY 0.680851 (-4875 2700);
PAINT MONO (-4875 2700);
DISPLAY INVISIBLE (-4875 2700);
FORCEPROP 2 LAST CDS_SEC 1
J 0
(-4875 2775);
DISPLAY 0.680851 (-4875 2775);
DISPLAY INVISIBLE (-4875 2775);
FORCEPROP 1 LASTPIN (-4925 2675) $PN 1
J 0
(-4915 2655);
DISPLAY 0.489362 (-4915 2655);
PAINT MONO (-4915 2655);
FORCEPROP 1 LASTPIN (-4925 2475) $PN 2
J 0
(-4915 2455);
DISPLAY 0.489362 (-4915 2455);
PAINT MONO (-4915 2455);
FORCEPROP 1 LAST VALUE 0.1UF
J 0
(-4875 2600);
DISPLAY 0.489362 (-4875 2600);
PAINT SKYBLUE (-4875 2600);
FORCEPROP 1 LAST PACK_TYPE 0402
J 0
(-4875 2350);
DISPLAY 0.489362 (-4875 2350);
PAINT SKYBLUE (-4875 2350);
FORCEPROP 1 LAST VOLTAGE 25V
J 0
(-4875 2550);
DISPLAY 0.489362 (-4875 2550);
PAINT SKYBLUE (-4875 2550);
FORCEPROP 1 LAST MATERIAL X7R
J 0
(-4875 2450);
DISPLAY 0.489362 (-4875 2450);
PAINT SKYBLUE (-4875 2450);
FORCEPROP 1 LAST TOLERANCE 10%
J 0
(-4875 2500);
DISPLAY 0.489362 (-4875 2500);
PAINT SKYBLUE (-4875 2500);
FORCEPROP 2 LAST CDS_LIB pure_quanta
J 0
(-4925 2575);
DISPLAY INVISIBLE (-4925 2575);
FORCEPROP 1 LAST PATH I25
J 0
(-4875 2725);
DISPLAY 0.978723 (-4875 2725);
PAINT WHITE (-4875 2725);
DISPLAY INVISIBLE (-4875 2725);
FORCEPROP 1 LAST PART_NUMBER CH4104K1B00
J 0
(-4875 2400);
DISPLAY 0.489362 (-4875 2400);
PAINT SKYBLUE (-4875 2400);
DISPLAY INVISIBLE (-4875 2400);
FORCEADD UNIVERSAL_GND..1
(-4925 2325);
FORCEPROP 3 LASTPIN (-4925 2375) SIG_NAME GND\g
J 0
(-4915 2385);
DISPLAY 0.659574 (-4915 2385);
PAINT MONO (-4915 2385);
DISPLAY INVISIBLE (-4915 2385);
FORCEPROP 2 LAST CDS_LIB pure_quanta_power
J 0
(-4925 2325);
DISPLAY INVISIBLE (-4925 2325);
FORCEPROP 1 LAST HDL_POWER GND
J 1
(-4900 2250);
DISPLAY 0.872340 (-4900 2250);
PAINT GREEN (-4900 2250);
DISPLAY INVISIBLE (-4900 2250);
FORCEPROP 1 LAST PATH I26
J 0
(-4850 2325);
DISPLAY 0.872340 (-4850 2325);
PAINT AQUA (-4850 2325);
DISPLAY INVISIBLE (-4850 2325);
FORCEADD UNIVERSAL_GND..1
(-4550 2325);
FORCEPROP 3 LASTPIN (-4550 2375) SIG_NAME GND\g
J 0
(-4540 2385);
DISPLAY 0.659574 (-4540 2385);
PAINT MONO (-4540 2385);
DISPLAY INVISIBLE (-4540 2385);
FORCEPROP 2 LAST CDS_LIB pure_quanta_power
J 0
(-4550 2325);
DISPLAY INVISIBLE (-4550 2325);
FORCEPROP 1 LAST HDL_POWER GND
J 1
(-4525 2250);
DISPLAY 0.872340 (-4525 2250);
PAINT GREEN (-4525 2250);
DISPLAY INVISIBLE (-4525 2250);
FORCEPROP 1 LAST PATH I27
J 0
(-4475 2325);
DISPLAY 0.872340 (-4475 2325);
PAINT AQUA (-4475 2325);
DISPLAY INVISIBLE (-4475 2325);
FORCEADD Q_RES..1
(-4525 3750);
FORCEPROP 1 LAST LOCATION PR6801
J 0
(-4575 3800);
DISPLAY 0.489362 (-4575 3800);
PAINT SKYBLUE (-4575 3800);
FORCEPROP 0 LAST $SEC 1
J 0
(-4575 3825);
DISPLAY 0.680851 (-4575 3825);
PAINT MONO (-4575 3825);
DISPLAY INVISIBLE (-4575 3825);
FORCEPROP 0 LAST CDS_SEC 1
J 0
(-4575 3825);
DISPLAY 0.680851 (-4575 3825);
DISPLAY INVISIBLE (-4575 3825);
FORCEPROP 1 LASTPIN (-4625 3750) $PN 1
J 0
(-4613 3762);
DISPLAY 0.787234 (-4613 3762);
PAINT MONO (-4613 3762);
FORCEPROP 1 LASTPIN (-4425 3750) $PN 2
J 0
(-4463 3762);
DISPLAY 0.787234 (-4463 3762);
PAINT MONO (-4463 3762);
FORCEPROP 1 LAST MATERIAL CHIP
J 0
(-4425 3675);
DISPLAY 0.489362 (-4425 3675);
PAINT SKYBLUE (-4425 3675);
FORCEPROP 1 LAST VALUE 2.2
J 2
(-4475 3700);
DISPLAY 0.489362 (-4475 3700);
PAINT SKYBLUE (-4475 3700);
FORCEPROP 1 LAST PACK_TYPE 0402LF
J 0
(-4450 3700);
DISPLAY 0.489362 (-4450 3700);
PAINT SKYBLUE (-4450 3700);
FORCEPROP 1 LAST TOLERANCE 1%
J 0
(-4405 3769);
DISPLAY 0.978723 (-4405 3769);
PAINT SKYBLUE (-4405 3769);
DISPLAY INVISIBLE (-4405 3769);
FORCEPROP 1 LAST WATTAGE 1/16W
J 2
(-3951 3768);
DISPLAY 0.978723 (-3951 3768);
PAINT SKYBLUE (-3951 3768);
DISPLAY INVISIBLE (-3951 3768);
FORCEPROP 2 LAST CDS_LIB pure_quanta
J 0
(-4525 3750);
DISPLAY INVISIBLE (-4525 3750);
FORCEPROP 1 LAST PATH I28
J 0
(-4575 3900);
DISPLAY 0.978723 (-4575 3900);
PAINT WHITE (-4575 3900);
DISPLAY INVISIBLE (-4575 3900);
FORCEPROP 1 LAST PART_NUMBER CS-2202FB01
J 0
(-4825 3700);
DISPLAY 0.489362 (-4825 3700);
PAINT SKYBLUE (-4825 3700);
DISPLAY INVISIBLE (-4825 3700);
FORCEADD Q_RES..2
(-4625 4250);
FORCEPROP 1 LAST LOCATION R644
J 0
(-4580 4375);
DISPLAY 0.489362 (-4580 4375);
PAINT SKYBLUE (-4580 4375);
FORCEPROP 2 LAST SEC 1
J 0
(-4574 4479);
DISPLAY 0.680851 (-4574 4479);
PAINT MONO (-4574 4479);
DISPLAY INVISIBLE (-4574 4479);
FORCEPROP 1 LASTPIN (-4625 4350) $PN 1
J 0
(-4620 4312);
DISPLAY 0.489362 (-4620 4312);
FORCEPROP 1 LASTPIN (-4625 4150) $PN 2
J 0
(-4620 4160);
DISPLAY 0.489362 (-4620 4160);
FORCEPROP 1 LAST MATERIAL CHIP
J 0
(-4585 4175);
DISPLAY 0.489362 (-4585 4175);
PAINT SKYBLUE (-4585 4175);
FORCEPROP 1 LAST WATTAGE 1/16W
J 0
(-4585 4225);
DISPLAY 0.489362 (-4585 4225);
PAINT SKYBLUE (-4585 4225);
FORCEPROP 1 LAST TOLERANCE 5%
J 0
(-4580 4275);
DISPLAY 0.489362 (-4580 4275);
PAINT SKYBLUE (-4580 4275);
FORCEPROP 1 LAST VALUE 10K
J 0
(-4580 4325);
DISPLAY 0.489362 (-4580 4325);
PAINT SKYBLUE (-4580 4325);
FORCEPROP 1 LAST PACK_TYPE 0402LF
J 0
(-4585 4075);
DISPLAY 0.489362 (-4585 4075);
PAINT SKYBLUE (-4585 4075);
FORCEPROP 2 LAST CDS_LIB pure_quanta
R 3
J 0
(-4625 4250);
PAINT MONO (-4625 4250);
DISPLAY INVISIBLE (-4625 4250);
FORCEPROP 2 LAST SEC_TYPE 0402LF
J 0
(-4574 4479);
DISPLAY 1.021277 (-4574 4479);
DISPLAY INVISIBLE (-4574 4479);
FORCEPROP 1 LAST PATH I29
J 0
(-4575 4425);
DISPLAY 0.978723 (-4575 4425);
PAINT WHITE (-4575 4425);
DISPLAY INVISIBLE (-4575 4425);
FORCEPROP 1 LAST PART_NUMBER CS31002JB08
J 0
(-4585 4125);
DISPLAY 0.489362 (-4585 4125);
PAINT SKYBLUE (-4585 4125);
DISPLAY INVISIBLE (-4585 4125);
FORCEADD Q_CAP..1
(-9150 4025);
FORCEPROP 1 LAST LOCATION PC6519
J 0
(-9100 4125);
DISPLAY 0.489362 (-9100 4125);
PAINT SKYBLUE (-9100 4125);
FORCEPROP 0 LAST $SEC 1
J 0
(-9100 4150);
DISPLAY 0.680851 (-9100 4150);
PAINT MONO (-9100 4150);
DISPLAY INVISIBLE (-9100 4150);
FORCEPROP 0 LAST CDS_SEC 1
J 0
(-9100 4150);
DISPLAY 0.680851 (-9100 4150);
DISPLAY INVISIBLE (-9100 4150);
FORCEPROP 1 LASTPIN (-9150 4125) $PN 1
J 0
(-9140 4105);
DISPLAY 0.787234 (-9140 4105);
PAINT MONO (-9140 4105);
FORCEPROP 1 LASTPIN (-9150 3925) $PN 2
J 0
(-9140 3905);
DISPLAY 0.787234 (-9140 3905);
PAINT MONO (-9140 3905);
FORCEPROP 1 LAST MATERIAL X6S
J 0
(-9100 3925);
DISPLAY 0.489362 (-9100 3925);
PAINT SKYBLUE (-9100 3925);
FORCEPROP 1 LAST VALUE 0.1UF
J 0
(-9100 4075);
DISPLAY 0.489362 (-9100 4075);
PAINT SKYBLUE (-9100 4075);
FORCEPROP 1 LAST PACK_TYPE C0402
J 0
(-9100 3825);
DISPLAY 0.489362 (-9100 3825);
PAINT SKYBLUE (-9100 3825);
FORCEPROP 1 LAST VOLTAGE 25V
J 0
(-9100 4025);
DISPLAY 0.489362 (-9100 4025);
PAINT SKYBLUE (-9100 4025);
FORCEPROP 1 LAST TOLERANCE 10%
J 0
(-9100 3975);
DISPLAY 0.489362 (-9100 3975);
PAINT SKYBLUE (-9100 3975);
FORCEPROP 2 LAST CDS_LIB pure_quanta
J 0
(-9150 4025);
DISPLAY INVISIBLE (-9150 4025);
FORCEPROP 1 LAST PATH I3
J 0
(-9100 4175);
DISPLAY 0.978723 (-9100 4175);
PAINT WHITE (-9100 4175);
DISPLAY INVISIBLE (-9100 4175);
FORCEPROP 1 LAST PART_NUMBER CH4104KEB00
J 0
(-9100 3875);
DISPLAY 0.489362 (-9100 3875);
PAINT SKYBLUE (-9100 3875);
DISPLAY INVISIBLE (-9100 3875);
FORCEADD UNIVERSAL_POWER..1
(-4625 4525);
FORCEPROP 3 LASTPIN (-4625 4475) SIG_NAME P3V3_AUX\g
J 0
(-4615 4485);
DISPLAY 0.659574 (-4615 4485);
PAINT MONO (-4615 4485);
DISPLAY INVISIBLE (-4615 4485);
FORCEPROP 1 LAST HDL_POWER P3V3_AUX
J 1
(-4625 4575);
DISPLAY 0.489362 (-4625 4575);
PAINT GREEN (-4625 4575);
FORCEPROP 2 LAST CDS_LIB mstr_symbols
J 0
(-4625 4525);
DISPLAY INVISIBLE (-4625 4525);
FORCEPROP 1 LAST PATH I30
J 0
(-4575 4550);
DISPLAY 0.872340 (-4575 4550);
PAINT AQUA (-4575 4550);
DISPLAY INVISIBLE (-4575 4550);
FORCEADD UNIVERSAL_GND..1
(-4075 2200);
FORCEPROP 3 LASTPIN (-4075 2250) SIG_NAME GND\g
J 0
(-4065 2260);
DISPLAY 0.659574 (-4065 2260);
PAINT MONO (-4065 2260);
DISPLAY INVISIBLE (-4065 2260);
FORCEPROP 2 LAST CDS_LIB pure_quanta_power
J 0
(-4075 2200);
DISPLAY INVISIBLE (-4075 2200);
FORCEPROP 1 LAST HDL_POWER GND
J 1
(-4050 2125);
DISPLAY 0.872340 (-4050 2125);
PAINT GREEN (-4050 2125);
DISPLAY INVISIBLE (-4050 2125);
FORCEPROP 1 LAST PATH I31
J 0
(-4000 2200);
DISPLAY 0.872340 (-4000 2200);
PAINT AQUA (-4000 2200);
DISPLAY INVISIBLE (-4000 2200);
FORCEADD Q_RES..2
(-4075 2475);
FORCEPROP 1 LAST LOCATION PR6526
J 0
(-4030 2600);
DISPLAY 0.489362 (-4030 2600);
PAINT SKYBLUE (-4030 2600);
FORCEPROP 2 LAST $SEC 1
J 0
(-4025 2700);
DISPLAY 0.680851 (-4025 2700);
PAINT MONO (-4025 2700);
DISPLAY INVISIBLE (-4025 2700);
FORCEPROP 2 LAST CDS_SEC 1
J 0
(-4025 2700);
DISPLAY 0.680851 (-4025 2700);
DISPLAY INVISIBLE (-4025 2700);
FORCEPROP 1 LASTPIN (-4075 2575) $PN 1
J 0
(-4070 2537);
DISPLAY 0.489362 (-4070 2537);
FORCEPROP 1 LASTPIN (-4075 2375) $PN 2
J 0
(-4070 2385);
DISPLAY 0.489362 (-4070 2385);
FORCEPROP 1 LAST PACK_TYPE 0402LF
J 0
(-4035 2300);
DISPLAY 0.489362 (-4035 2300);
PAINT SKYBLUE (-4035 2300);
FORCEPROP 1 LAST MATERIAL CHIP
J 0
(-4035 2400);
DISPLAY 0.489362 (-4035 2400);
PAINT SKYBLUE (-4035 2400);
FORCEPROP 1 LAST WATTAGE 1/16W
J 0
(-4035 2450);
DISPLAY 0.489362 (-4035 2450);
PAINT SKYBLUE (-4035 2450);
FORCEPROP 1 LAST TOLERANCE 1%
J 0
(-4030 2500);
DISPLAY 0.489362 (-4030 2500);
PAINT SKYBLUE (-4030 2500);
FORCEPROP 1 LAST VALUE 10K
J 0
(-4030 2550);
DISPLAY 0.489362 (-4030 2550);
PAINT SKYBLUE (-4030 2550);
FORCEPROP 2 LAST CDS_LIB pure_quanta
J 0
(-4075 2475);
DISPLAY INVISIBLE (-4075 2475);
FORCEPROP 1 LAST PATH I32
J 0
(-4025 2650);
DISPLAY 0.978723 (-4025 2650);
PAINT WHITE (-4025 2650);
DISPLAY INVISIBLE (-4025 2650);
FORCEPROP 1 LAST PART_NUMBER CS31002FB08
J 0
(-4035 2350);
DISPLAY 0.489362 (-4035 2350);
PAINT SKYBLUE (-4035 2350);
DISPLAY INVISIBLE (-4035 2350);
FORCEADD Q_CAP..2
(-3500 2675);
FORCEPROP 1 LAST LOCATION PC6534
J 1
(-3500 2750);
DISPLAY 0.489362 (-3500 2750);
PAINT SKYBLUE (-3500 2750);
FORCEPROP 0 LAST $SEC 1
J 0
(-3500 2825);
DISPLAY 0.680851 (-3500 2825);
PAINT MONO (-3500 2825);
DISPLAY INVISIBLE (-3500 2825);
FORCEPROP 0 LAST CDS_SEC 1
J 0
(-3500 2825);
DISPLAY 0.680851 (-3500 2825);
DISPLAY INVISIBLE (-3500 2825);
FORCEPROP 1 LASTPIN (-3600 2675) $PN 1
J 0
(-3610 2690);
DISPLAY 0.489362 (-3610 2690);
PAINT MONO (-3610 2690);
FORCEPROP 1 LASTPIN (-3400 2675) $PN 2
J 0
(-3415 2690);
DISPLAY 0.489362 (-3415 2690);
PAINT MONO (-3415 2690);
FORCEPROP 1 LAST MATERIAL NPO
J 0
(-3425 2600);
DISPLAY 0.489362 (-3425 2600);
PAINT SKYBLUE (-3425 2600);
FORCEPROP 1 LAST TOLERANCE 5%
J 2
(-3625 2550);
DISPLAY 0.489362 (-3625 2550);
PAINT SKYBLUE (-3625 2550);
FORCEPROP 1 LAST VALUE 150PF
J 2
(-3575 2725);
DISPLAY 0.489362 (-3575 2725);
PAINT SKYBLUE (-3575 2725);
FORCEPROP 1 LAST PACK_TYPE 0402
J 1
(-3375 2550);
DISPLAY 0.489362 (-3375 2550);
PAINT SKYBLUE (-3375 2550);
FORCEPROP 1 LAST VOLTAGE 50V
J 0
(-3400 2725);
DISPLAY 0.489362 (-3400 2725);
PAINT SKYBLUE (-3400 2725);
FORCEPROP 2 LAST CDS_LIB pure_quanta
J 0
(-3500 2675);
DISPLAY INVISIBLE (-3500 2675);
FORCEPROP 1 LAST PATH I33
J 0
(-3500 2875);
DISPLAY 0.978723 (-3500 2875);
PAINT WHITE (-3500 2875);
DISPLAY INVISIBLE (-3500 2875);
FORCEPROP 1 LAST PART_NUMBER TMP_QCH11506JB08
J 1
(-3700 2600);
DISPLAY 0.489362 (-3700 2600);
PAINT SKYBLUE (-3700 2600);
DISPLAY INVISIBLE (-3700 2600);
FORCEADD Q_RES..1
(-3500 3000);
FORCEPROP 1 LAST LOCATION PR6524
J 0
(-3550 3050);
DISPLAY 0.489362 (-3550 3050);
PAINT SKYBLUE (-3550 3050);
FORCEPROP 2 LAST $SEC 1
J 0
(-3527 3213);
DISPLAY 0.680851 (-3527 3213);
PAINT MONO (-3527 3213);
DISPLAY INVISIBLE (-3527 3213);
FORCEPROP 2 LAST CDS_SEC 1
J 0
(-3527 3213);
DISPLAY 0.680851 (-3527 3213);
DISPLAY INVISIBLE (-3527 3213);
FORCEPROP 1 LASTPIN (-3600 3000) $PN 1
J 0
(-3588 3012);
DISPLAY 0.489362 (-3588 3012);
FORCEPROP 1 LASTPIN (-3400 3000) $PN 2
J 0
(-3438 3012);
DISPLAY 0.489362 (-3438 3012);
FORCEPROP 1 LAST MATERIAL CHIP
J 0
(-3325 3050);
DISPLAY 0.489362 (-3325 3050);
PAINT SKYBLUE (-3325 3050);
FORCEPROP 1 LAST VALUE 20K
J 2
(-3625 3050);
DISPLAY 0.489362 (-3625 3050);
PAINT SKYBLUE (-3625 3050);
FORCEPROP 1 LAST PACK_TYPE 0402LF
J 0
(-3325 2950);
DISPLAY 0.489362 (-3325 2950);
PAINT SKYBLUE (-3325 2950);
FORCEPROP 2 LAST CDS_LIB pure_quanta
J 0
(-3500 3000);
DISPLAY INVISIBLE (-3500 3000);
FORCEPROP 1 LAST WATTAGE 1/16W
J 2
(-2926 3018);
DISPLAY 0.978723 (-2926 3018);
PAINT SKYBLUE (-2926 3018);
DISPLAY INVISIBLE (-2926 3018);
FORCEPROP 1 LAST TOLERANCE 1%
J 0
(-3380 3019);
DISPLAY 0.978723 (-3380 3019);
PAINT SKYBLUE (-3380 3019);
DISPLAY INVISIBLE (-3380 3019);
FORCEPROP 1 LAST PATH I34
J 0
(-3550 3150);
DISPLAY 0.978723 (-3550 3150);
PAINT WHITE (-3550 3150);
DISPLAY INVISIBLE (-3550 3150);
FORCEPROP 1 LAST PART_NUMBER CS32002FB06
J 0
(-3750 2950);
DISPLAY 0.489362 (-3750 2950);
PAINT SKYBLUE (-3750 2950);
DISPLAY INVISIBLE (-3750 2950);
FORCEADD Q_CAP..1
(-3925 3625);
FORCEPROP 1 LAST LOCATION PC6526
J 0
(-3875 3800);
DISPLAY 0.489362 (-3875 3800);
PAINT SKYBLUE (-3875 3800);
FORCEPROP 2 LAST SEC 1
J 0
(-3851 3844);
DISPLAY 0.680851 (-3851 3844);
PAINT MONO (-3851 3844);
DISPLAY INVISIBLE (-3851 3844);
FORCEPROP 1 LASTPIN (-3925 3725) $PN 1
J 0
(-3915 3705);
DISPLAY 0.489362 (-3915 3705);
FORCEPROP 1 LASTPIN (-3925 3525) $PN 2
J 0
(-3915 3505);
DISPLAY 0.489362 (-3915 3505);
FORCEPROP 1 LAST TOLERANCE 10%
J 0
(-3875 3650);
DISPLAY 0.489362 (-3875 3650);
PAINT SKYBLUE (-3875 3650);
FORCEPROP 1 LAST MATERIAL X7R
J 0
(-3875 3600);
DISPLAY 0.489362 (-3875 3600);
PAINT SKYBLUE (-3875 3600);
FORCEPROP 1 LAST VOLTAGE 16V
J 0
(-3875 3700);
DISPLAY 0.489362 (-3875 3700);
PAINT SKYBLUE (-3875 3700);
FORCEPROP 1 LAST PACK_TYPE 0402
J 0
(-3875 3500);
DISPLAY 0.489362 (-3875 3500);
PAINT SKYBLUE (-3875 3500);
FORCEPROP 1 LAST VALUE 0.22UF
J 0
(-3875 3750);
DISPLAY 0.489362 (-3875 3750);
PAINT SKYBLUE (-3875 3750);
FORCEPROP 2 LAST SEC_TYPE 0402
J 0
(-3851 3844);
DISPLAY 1.021277 (-3851 3844);
DISPLAY INVISIBLE (-3851 3844);
FORCEPROP 2 LAST CDS_LIB pure_quanta
J 0
(-3925 3625);
PAINT MONO (-3925 3625);
DISPLAY INVISIBLE (-3925 3625);
FORCEPROP 1 LAST PATH I35
J 0
(-3875 3775);
DISPLAY 0.978723 (-3875 3775);
PAINT WHITE (-3875 3775);
DISPLAY INVISIBLE (-3875 3775);
FORCEPROP 1 LAST PART_NUMBER CH4223K1B00
J 0
(-3875 3550);
DISPLAY 0.489362 (-3875 3550);
PAINT SKYBLUE (-3875 3550);
DISPLAY INVISIBLE (-3875 3550);
FORCEADD Q_RES..1
(-3575 3950);
FORCEPROP 1 LAST LOCATION R645
J 0
(-3450 3950);
DISPLAY 0.489362 (-3450 3950);
PAINT SKYBLUE (-3450 3950);
FORCEPROP 0 LAST $SEC 1
J 2
(-3450 4000);
DISPLAY 0.680851 (-3450 4000);
PAINT MONO (-3450 4000);
DISPLAY INVISIBLE (-3450 4000);
FORCEPROP 0 LAST CDS_SEC 1
J 2
(-3450 4000);
DISPLAY 1.021277 (-3450 4000);
DISPLAY INVISIBLE (-3450 4000);
FORCEPROP 1 LASTPIN (-3675 3950) $PN 1
J 0
(-3663 3962);
DISPLAY 0.489362 (-3663 3962);
PAINT MONO (-3663 3962);
FORCEPROP 1 LASTPIN (-3475 3950) $PN 2
J 0
(-3513 3962);
DISPLAY 0.489362 (-3513 3962);
PAINT MONO (-3513 3962);
FORCEPROP 1 LAST VALUE 33
J 2
(-3700 3950);
DISPLAY 0.489362 (-3700 3950);
PAINT SKYBLUE (-3700 3950);
FORCEPROP 1 LAST PACK_TYPE 0402LF
J 2
(-3400 3875);
DISPLAY 0.489362 (-3400 3875);
PAINT SKYBLUE (-3400 3875);
DISPLAY INVISIBLE (-3400 3875);
FORCEPROP 1 LAST TOLERANCE 5%
J 0
(-3700 3925);
DISPLAY 0.489362 (-3700 3925);
PAINT SKYBLUE (-3700 3925);
DISPLAY INVISIBLE (-3700 3925);
FORCEPROP 1 LAST MATERIAL CHIP
J 2
(-3400 3925);
DISPLAY 0.489362 (-3400 3925);
PAINT SKYBLUE (-3400 3925);
DISPLAY INVISIBLE (-3400 3925);
FORCEPROP 1 LAST WATTAGE 1/16W
J 2
(-3650 3875);
DISPLAY 0.489362 (-3650 3875);
PAINT SKYBLUE (-3650 3875);
DISPLAY INVISIBLE (-3650 3875);
FORCEPROP 2 LAST BOM_COST MEM
J 2
(-3550 4100);
DISPLAY 0.744681 (-3550 4100);
PAINT WHITE (-3550 4100);
DISPLAY INVISIBLE (-3550 4100);
FORCEPROP 2 LAST CDS_LIB pure_quanta
J 2
(-3575 3950);
DISPLAY INVISIBLE (-3575 3950);
FORCEPROP 1 LAST PATH I36
J 0
(-3625 4100);
DISPLAY 0.978723 (-3625 4100);
PAINT WHITE (-3625 4100);
DISPLAY INVISIBLE (-3625 4100);
FORCEPROP 1 LAST PART_NUMBER CS03302JB10
J 2
(-3475 4000);
DISPLAY 0.489362 (-3475 4000);
PAINT SKYBLUE (-3475 4000);
DISPLAY INVISIBLE (-3475 4000);
FORCEADD Q_INDUCTOR..1
(-3500 3475);
FORCEPROP 1 LAST LOCATION PL6502
J 0
(-3625 3635);
DISPLAY 0.489362 (-3625 3635);
PAINT SKYBLUE (-3625 3635);
FORCEPROP 2 LAST $SEC 1
J 0
(-3625 3775);
DISPLAY 0.680851 (-3625 3775);
PAINT MONO (-3625 3775);
DISPLAY INVISIBLE (-3625 3775);
FORCEPROP 2 LAST CDS_SEC 1
J 0
(-3625 3775);
DISPLAY 0.680851 (-3625 3775);
DISPLAY INVISIBLE (-3625 3775);
FORCEPROP 2 LASTPIN (-3600 3450) $PN 1
J 2
(-3610 3460);
DISPLAY 0.489362 (-3610 3460);
FORCEPROP 2 LASTPIN (-3400 3450) $PN 2
J 0
(-3390 3460);
DISPLAY 0.489362 (-3390 3460);
FORCEPROP 2 LAST VALUE 1UH
J 0
(-3625 3675);
DISPLAY 0.489362 (-3625 3675);
PAINT SKYBLUE (-3625 3675);
FORCEPROP 1 LAST MATERIAL IND
J 0
(-3625 3530);
DISPLAY 0.489362 (-3625 3530);
PAINT SKYBLUE (-3625 3530);
FORCEPROP 2 LAST PACK_TYPE SMLF
J 0
(-3625 3725);
DISPLAY 0.489362 (-3625 3725);
PAINT SKYBLUE (-3625 3725);
FORCEPROP 1 LAST NEEDS_NO_SIZE TRUE
J 0
(-3500 3475);
DISPLAY 0.468085 (-3500 3475);
PAINT GREEN (-3500 3475);
DISPLAY INVISIBLE (-3500 3475);
FORCEPROP 2 LAST CDS_LIB pure_quanta
J 0
(-3500 3475);
DISPLAY INVISIBLE (-3500 3475);
FORCEPROP 1 LAST PATH I37
J 0
(-3425 3530);
DISPLAY 0.723404 (-3425 3530);
PAINT GREEN (-3425 3530);
DISPLAY INVISIBLE (-3425 3530);
FORCEPROP 1 LAST PART_NUMBER CV-10U0MZ01
J 0
(-3625 3585);
DISPLAY 0.489362 (-3625 3585);
PAINT SKYBLUE (-3625 3585);
DISPLAY INVISIBLE (-3625 3585);
FORCEADD Q_CAP..1
(-2850 3200);
FORCEPROP 1 LAST LOCATION PC6527
J 0
(-2800 3300);
DISPLAY 0.489362 (-2800 3300);
PAINT SKYBLUE (-2800 3300);
FORCEPROP 0 LAST $SEC 1
J 0
(-2800 3325);
DISPLAY 0.680851 (-2800 3325);
PAINT MONO (-2800 3325);
DISPLAY INVISIBLE (-2800 3325);
FORCEPROP 0 LAST CDS_SEC 1
J 0
(-2800 3325);
DISPLAY 1.021277 (-2800 3325);
DISPLAY INVISIBLE (-2800 3325);
FORCEPROP 1 LASTPIN (-2850 3300) $PN 1
J 0
(-2840 3280);
DISPLAY 0.489362 (-2840 3280);
PAINT MONO (-2840 3280);
FORCEPROP 1 LASTPIN (-2850 3100) $PN 2
J 0
(-2840 3080);
DISPLAY 0.489362 (-2840 3080);
PAINT MONO (-2840 3080);
FORCEPROP 1 LAST VOLTAGE 4V
J 0
(-2800 3200);
DISPLAY 0.489362 (-2800 3200);
PAINT SKYBLUE (-2800 3200);
FORCEPROP 1 LAST TOLERANCE 20%
J 0
(-2800 3150);
DISPLAY 0.489362 (-2800 3150);
PAINT SKYBLUE (-2800 3150);
FORCEPROP 1 LAST MATERIAL X6S
J 0
(-2800 3100);
DISPLAY 0.489362 (-2800 3100);
PAINT SKYBLUE (-2800 3100);
FORCEPROP 1 LAST VALUE 22UF
J 0
(-2800 3250);
DISPLAY 0.489362 (-2800 3250);
PAINT SKYBLUE (-2800 3250);
FORCEPROP 1 LAST PACK_TYPE C0805
J 0
(-2800 3000);
DISPLAY 0.489362 (-2800 3000);
PAINT SKYBLUE (-2800 3000);
FORCEPROP 2 LAST CDS_LIB pure_quanta
J 0
(-2850 3200);
DISPLAY INVISIBLE (-2850 3200);
FORCEPROP 1 LAST PATH I38
J 0
(-2800 3350);
DISPLAY 0.978723 (-2800 3350);
PAINT WHITE (-2800 3350);
DISPLAY INVISIBLE (-2800 3350);
FORCEPROP 1 LAST PART_NUMBER CH622KMEA03
J 0
(-2800 3050);
DISPLAY 0.489362 (-2800 3050);
PAINT SKYBLUE (-2800 3050);
DISPLAY INVISIBLE (-2800 3050);
FORCEADD Q_CAP..1
(-2775 3800);
FORCEPROP 1 LAST LOCATION C109
J 0
(-2725 3900);
DISPLAY 0.638298 (-2725 3900);
FORCEPROP 0 LAST $SEC 1
J 0
(-2725 3950);
DISPLAY 0.680851 (-2725 3950);
PAINT MONO (-2725 3950);
DISPLAY INVISIBLE (-2725 3950);
FORCEPROP 0 LAST CDS_SEC 1
J 0
(-2725 3950);
DISPLAY 0.680851 (-2725 3950);
DISPLAY INVISIBLE (-2725 3950);
FORCEPROP 1 LASTPIN (-2775 3900) $PN 1
J 0
(-2765 3880);
DISPLAY 0.787234 (-2765 3880);
PAINT MONO (-2765 3880);
FORCEPROP 1 LASTPIN (-2775 3700) $PN 2
J 0
(-2765 3680);
DISPLAY 0.787234 (-2765 3680);
PAINT MONO (-2765 3680);
FORCEPROP 1 LAST VOLTAGE 50V
J 0
(-2725 3800);
DISPLAY 0.638298 (-2725 3800);
FORCEPROP 1 LAST MATERIAL X7R
J 0
(-2725 3700);
DISPLAY 0.638298 (-2725 3700);
FORCEPROP 1 LAST VALUE 1000PF
J 0
(-2725 3850);
DISPLAY 0.638298 (-2725 3850);
FORCEPROP 1 LAST TOLERANCE 5%
J 0
(-2725 3750);
DISPLAY 0.638298 (-2725 3750);
FORCEPROP 1 LAST PACK_TYPE 0402
J 0
(-2725 3600);
DISPLAY 0.638298 (-2725 3600);
FORCEPROP 2 LAST CDS_LIB pure_quanta
J 0
(-2775 3800);
DISPLAY INVISIBLE (-2775 3800);
FORCEPROP 1 LAST PATH I39
J 0
(-2725 3950);
DISPLAY 0.978723 (-2725 3950);
PAINT WHITE (-2725 3950);
DISPLAY INVISIBLE (-2725 3950);
FORCEPROP 1 LAST PART_NUMBER TMP_QCH21006JB10
J 0
(-2725 3650);
DISPLAY 0.638298 (-2725 3650);
DISPLAY INVISIBLE (-2725 3650);
FORCEADD UNIVERSAL_GND..1
(-8500 3050);
FORCEPROP 3 LASTPIN (-8500 3100) SIG_NAME GND\g
J 0
(-8490 3110);
DISPLAY 0.659574 (-8490 3110);
PAINT MONO (-8490 3110);
DISPLAY INVISIBLE (-8490 3110);
FORCEPROP 2 LAST CDS_LIB pure_quanta_power
J 0
(-8500 3050);
DISPLAY INVISIBLE (-8500 3050);
FORCEPROP 1 LAST HDL_POWER GND
J 1
(-8475 2975);
DISPLAY 0.872340 (-8475 2975);
PAINT GREEN (-8475 2975);
DISPLAY INVISIBLE (-8475 2975);
FORCEPROP 1 LAST PATH I4
J 0
(-8425 3050);
DISPLAY 0.872340 (-8425 3050);
PAINT AQUA (-8425 3050);
DISPLAY INVISIBLE (-8425 3050);
FORCEADD UNIVERSAL_GND..1
(-2775 3600);
FORCEPROP 3 LASTPIN (-2775 3650) SIG_NAME GND\g
J 0
(-2765 3660);
DISPLAY 0.659574 (-2765 3660);
PAINT MONO (-2765 3660);
DISPLAY INVISIBLE (-2765 3660);
FORCEPROP 2 LAST CDS_LIB pure_quanta_power
J 0
(-2775 3600);
DISPLAY INVISIBLE (-2775 3600);
FORCEPROP 1 LAST HDL_POWER GND
J 1
(-2750 3525);
DISPLAY 0.872340 (-2750 3525);
PAINT GREEN (-2750 3525);
DISPLAY INVISIBLE (-2750 3525);
FORCEPROP 1 LAST PATH I40
J 0
(-2700 3600);
DISPLAY 0.872340 (-2700 3600);
PAINT AQUA (-2700 3600);
DISPLAY INVISIBLE (-2700 3600);
FORCEADD Q_CAP..1
(-2425 3200);
FORCEPROP 1 LAST LOCATION PC6528
J 0
(-2375 3300);
DISPLAY 0.489362 (-2375 3300);
PAINT SKYBLUE (-2375 3300);
FORCEPROP 0 LAST $SEC 1
J 0
(-2375 3350);
DISPLAY 0.680851 (-2375 3350);
PAINT MONO (-2375 3350);
DISPLAY INVISIBLE (-2375 3350);
FORCEPROP 0 LAST CDS_SEC 1
J 0
(-2375 3350);
DISPLAY 1.021277 (-2375 3350);
DISPLAY INVISIBLE (-2375 3350);
FORCEPROP 1 LASTPIN (-2425 3300) $PN 1
J 0
(-2415 3280);
DISPLAY 0.489362 (-2415 3280);
PAINT MONO (-2415 3280);
FORCEPROP 1 LASTPIN (-2425 3100) $PN 2
J 0
(-2415 3080);
DISPLAY 0.489362 (-2415 3080);
PAINT MONO (-2415 3080);
FORCEPROP 1 LAST MATERIAL X6S
J 0
(-2375 3100);
DISPLAY 0.489362 (-2375 3100);
PAINT SKYBLUE (-2375 3100);
FORCEPROP 1 LAST PACK_TYPE C0805
J 0
(-2375 3050);
DISPLAY 0.489362 (-2375 3050);
PAINT SKYBLUE (-2375 3050);
FORCEPROP 1 LAST VOLTAGE 4V
J 0
(-2375 3200);
DISPLAY 0.489362 (-2375 3200);
PAINT SKYBLUE (-2375 3200);
FORCEPROP 1 LAST TOLERANCE 20%
J 0
(-2375 3150);
DISPLAY 0.489362 (-2375 3150);
PAINT SKYBLUE (-2375 3150);
FORCEPROP 1 LAST VALUE 22UF
J 0
(-2375 3250);
DISPLAY 0.489362 (-2375 3250);
PAINT SKYBLUE (-2375 3250);
FORCEPROP 2 LAST CDS_LIB pure_quanta
J 0
(-2425 3200);
DISPLAY INVISIBLE (-2425 3200);
FORCEPROP 1 LAST PATH I41
J 0
(-2375 3350);
DISPLAY 0.978723 (-2375 3350);
PAINT WHITE (-2375 3350);
DISPLAY INVISIBLE (-2375 3350);
FORCEPROP 1 LAST PART_NUMBER CH622KMEA03
J 0
(-2375 3050);
DISPLAY 0.489362 (-2375 3050);
PAINT SKYBLUE (-2375 3050);
DISPLAY INVISIBLE (-2375 3050);
FORCEADD Q_CAP..1
(-2150 3200);
FORCEPROP 1 LAST LOCATION PC6529
J 0
(-2100 3300);
DISPLAY 0.489362 (-2100 3300);
PAINT SKYBLUE (-2100 3300);
FORCEPROP 0 LAST $SEC 1
J 0
(-2100 3350);
DISPLAY 0.680851 (-2100 3350);
PAINT MONO (-2100 3350);
DISPLAY INVISIBLE (-2100 3350);
FORCEPROP 0 LAST CDS_SEC 1
J 0
(-2100 3350);
DISPLAY 1.021277 (-2100 3350);
DISPLAY INVISIBLE (-2100 3350);
FORCEPROP 1 LASTPIN (-2150 3300) $PN 1
J 0
(-2140 3280);
DISPLAY 0.489362 (-2140 3280);
PAINT MONO (-2140 3280);
FORCEPROP 1 LASTPIN (-2150 3100) $PN 2
J 0
(-2140 3080);
DISPLAY 0.489362 (-2140 3080);
PAINT MONO (-2140 3080);
FORCEPROP 1 LAST MATERIAL X6S
J 0
(-2100 3100);
DISPLAY 0.489362 (-2100 3100);
PAINT SKYBLUE (-2100 3100);
FORCEPROP 1 LAST TOLERANCE 20%
J 0
(-2100 3150);
DISPLAY 0.489362 (-2100 3150);
PAINT SKYBLUE (-2100 3150);
FORCEPROP 1 LAST PACK_TYPE C0805
J 0
(-2100 3050);
DISPLAY 0.489362 (-2100 3050);
PAINT SKYBLUE (-2100 3050);
FORCEPROP 1 LAST VOLTAGE 4V
J 0
(-2100 3200);
DISPLAY 0.489362 (-2100 3200);
PAINT SKYBLUE (-2100 3200);
FORCEPROP 1 LAST VALUE 22UF
J 0
(-2100 3250);
DISPLAY 0.489362 (-2100 3250);
PAINT SKYBLUE (-2100 3250);
FORCEPROP 2 LAST CDS_LIB pure_quanta
J 0
(-2150 3200);
DISPLAY INVISIBLE (-2150 3200);
FORCEPROP 1 LAST PATH I42
J 0
(-2100 3350);
DISPLAY 0.978723 (-2100 3350);
PAINT WHITE (-2100 3350);
DISPLAY INVISIBLE (-2100 3350);
FORCEPROP 1 LAST PART_NUMBER CH622KMEA03
J 0
(-2100 3050);
DISPLAY 0.489362 (-2100 3050);
PAINT SKYBLUE (-2100 3050);
DISPLAY INVISIBLE (-2100 3050);
FORCEADD OFFPAGE..2
(-2525 3950);
FORCEPROP 2 LAST $XR0 81 
J 0
(-2336 3950);
DISPLAY 0.638298 (-2336 3950);
PAINT MONO (-2336 3950);
FORCEPROP 2 LAST ROOM VR_CORE0_CTRL
J 2
(-2250 4000);
PAINT RED (-2250 4000);
DISPLAY INVISIBLE (-2250 4000);
FORCEPROP 2 LAST CDS_LIB standard
J 0
(-2525 3950);
DISPLAY INVISIBLE (-2525 3950);
FORCEPROP 1 LAST OFFPAGE TRUE
J 0
(-2200 3825);
DISPLAY 1.170213 (-2200 3825);
PAINT GREEN (-2200 3825);
DISPLAY INVISIBLE (-2200 3825);
FORCEPROP 1 LAST COMMENT_BODY TRUE
J 0
(-2570 3855);
DISPLAY 1.170213 (-2570 3855);
PAINT GREEN (-2570 3855);
DISPLAY INVISIBLE (-2570 3855);
FORCEPROP 2 LAST PATH I43
J 0
(-2350 4025);
DISPLAY 0.680851 (-2350 4025);
DISPLAY INVISIBLE (-2350 4025);
FORCEADD Q_CAP..1
(-1900 3200);
FORCEPROP 1 LAST LOCATION PC6530
J 0
(-1850 3300);
DISPLAY 0.489362 (-1850 3300);
PAINT SKYBLUE (-1850 3300);
FORCEPROP 0 LAST $SEC 1
J 0
(-1850 3350);
DISPLAY 0.680851 (-1850 3350);
PAINT MONO (-1850 3350);
DISPLAY INVISIBLE (-1850 3350);
FORCEPROP 0 LAST CDS_SEC 1
J 0
(-1850 3350);
DISPLAY 0.680851 (-1850 3350);
DISPLAY INVISIBLE (-1850 3350);
FORCEPROP 1 LASTPIN (-1900 3300) $PN 1
J 0
(-1890 3280);
DISPLAY 0.489362 (-1890 3280);
PAINT MONO (-1890 3280);
FORCEPROP 1 LASTPIN (-1900 3100) $PN 2
J 0
(-1890 3080);
DISPLAY 0.489362 (-1890 3080);
PAINT MONO (-1890 3080);
FORCEPROP 1 LAST TOLERANCE 20%
J 0
(-1850 3150);
DISPLAY 0.489362 (-1850 3150);
PAINT SKYBLUE (-1850 3150);
FORCEPROP 1 LAST VOLTAGE 4V
J 0
(-1850 3200);
DISPLAY 0.489362 (-1850 3200);
PAINT SKYBLUE (-1850 3200);
FORCEPROP 1 LAST PACK_TYPE C0805
J 0
(-1850 3050);
DISPLAY 0.489362 (-1850 3050);
PAINT SKYBLUE (-1850 3050);
FORCEPROP 1 LAST VALUE 22UF
J 0
(-1850 3250);
DISPLAY 0.489362 (-1850 3250);
PAINT SKYBLUE (-1850 3250);
FORCEPROP 1 LAST MATERIAL X6S
J 0
(-1850 3100);
DISPLAY 0.489362 (-1850 3100);
PAINT RED (-1850 3100);
FORCEPROP 2 LAST CDS_LIB pure_quanta
J 0
(-1900 3200);
DISPLAY INVISIBLE (-1900 3200);
FORCEPROP 1 LAST PATH I44
J 0
(-1850 3350);
DISPLAY 0.978723 (-1850 3350);
PAINT WHITE (-1850 3350);
DISPLAY INVISIBLE (-1850 3350);
FORCEPROP 1 LAST PART_NUMBER CH622KMEA03
J 0
(-1850 3050);
DISPLAY 0.489362 (-1850 3050);
PAINT SKYBLUE (-1850 3050);
DISPLAY INVISIBLE (-1850 3050);
FORCEADD Q_CAP..1
(-1625 3200);
FORCEPROP 1 LAST LOCATION PC6531
J 0
(-1575 3300);
DISPLAY 0.489362 (-1575 3300);
PAINT SKYBLUE (-1575 3300);
FORCEPROP 0 LAST $SEC 1
J 0
(-1575 3350);
DISPLAY 0.680851 (-1575 3350);
PAINT MONO (-1575 3350);
DISPLAY INVISIBLE (-1575 3350);
FORCEPROP 0 LAST CDS_SEC 1
J 0
(-1575 3350);
DISPLAY 0.680851 (-1575 3350);
DISPLAY INVISIBLE (-1575 3350);
FORCEPROP 1 LASTPIN (-1625 3300) $PN 1
J 0
(-1615 3280);
DISPLAY 0.489362 (-1615 3280);
PAINT MONO (-1615 3280);
FORCEPROP 1 LASTPIN (-1625 3100) $PN 2
J 0
(-1615 3080);
DISPLAY 0.489362 (-1615 3080);
PAINT MONO (-1615 3080);
FORCEPROP 1 LAST PACK_TYPE C0805
J 0
(-1575 3050);
DISPLAY 0.489362 (-1575 3050);
PAINT SKYBLUE (-1575 3050);
FORCEPROP 1 LAST VOLTAGE 4V
J 0
(-1575 3200);
DISPLAY 0.489362 (-1575 3200);
PAINT SKYBLUE (-1575 3200);
FORCEPROP 1 LAST VALUE 22UF
J 0
(-1575 3250);
DISPLAY 0.489362 (-1575 3250);
PAINT SKYBLUE (-1575 3250);
FORCEPROP 1 LAST MATERIAL X6S
J 0
(-1575 3100);
DISPLAY 0.489362 (-1575 3100);
PAINT RED (-1575 3100);
FORCEPROP 1 LAST TOLERANCE 20%
J 0
(-1575 3150);
DISPLAY 0.489362 (-1575 3150);
PAINT SKYBLUE (-1575 3150);
FORCEPROP 2 LAST CDS_LIB pure_quanta
J 0
(-1625 3200);
DISPLAY INVISIBLE (-1625 3200);
FORCEPROP 1 LAST PATH I45
J 0
(-1575 3350);
DISPLAY 0.978723 (-1575 3350);
PAINT WHITE (-1575 3350);
DISPLAY INVISIBLE (-1575 3350);
FORCEPROP 1 LAST PART_NUMBER CH622KMEA03
J 0
(-1575 3050);
DISPLAY 0.489362 (-1575 3050);
PAINT SKYBLUE (-1575 3050);
DISPLAY INVISIBLE (-1575 3050);
FORCEADD Q_CAPP..1
(-1350 3200);
FORCEPROP 1 LAST LOCATION PC6532
J 0
(-1300 3300);
DISPLAY 0.489362 (-1300 3300);
PAINT SKYBLUE (-1300 3300);
FORCEPROP 0 LAST $SEC 1
J 0
(-1300 3325);
DISPLAY 0.680851 (-1300 3325);
PAINT MONO (-1300 3325);
DISPLAY INVISIBLE (-1300 3325);
FORCEPROP 0 LAST CDS_SEC 1
J 0
(-1300 3325);
DISPLAY 1.021277 (-1300 3325);
DISPLAY INVISIBLE (-1300 3325);
FORCEPROP 1 LASTPIN (-1350 3300) $PN 1
J 0
(-1340 3285);
DISPLAY 0.489362 (-1340 3285);
PAINT MONO (-1340 3285);
FORCEPROP 1 LASTPIN (-1350 3100) $PN 2
J 0
(-1340 3085);
DISPLAY 0.489362 (-1340 3085);
PAINT MONO (-1340 3085);
FORCEPROP 1 LAST PACK_TYPE SMLF
J 0
(-1300 3050);
DISPLAY 0.489362 (-1300 3050);
PAINT SKYBLUE (-1300 3050);
FORCEPROP 1 LAST MATERIAL ALUM
J 0
(-1300 3100);
DISPLAY 0.489362 (-1300 3100);
PAINT SKYBLUE (-1300 3100);
FORCEPROP 1 LAST VALUE 390UF
J 0
(-1300 3250);
DISPLAY 0.489362 (-1300 3250);
PAINT SKYBLUE (-1300 3250);
FORCEPROP 1 LAST TOLERANCE 20%
J 0
(-1300 3200);
DISPLAY 0.489362 (-1300 3200);
PAINT SKYBLUE (-1300 3200);
FORCEPROP 1 LAST VOLTAGE 2.5V
J 0
(-1300 3150);
DISPLAY 0.489362 (-1300 3150);
PAINT SKYBLUE (-1300 3150);
FORCEPROP 2 LAST CDS_LIB pure_quanta
J 0
(-1350 3200);
DISPLAY INVISIBLE (-1350 3200);
FORCEPROP 1 LAST PATH I46
J 0
(-1300 3350);
DISPLAY 0.978723 (-1300 3350);
DISPLAY INVISIBLE (-1300 3350);
FORCEPROP 1 LAST PART_NUMBER CC7390JMZ13
J 0
(-1300 3000);
DISPLAY 0.489362 (-1300 3000);
PAINT SKYBLUE (-1300 3000);
DISPLAY INVISIBLE (-1300 3000);
FORCEADD Q_CAPP..1
(-1050 3200);
FORCEPROP 1 LAST LOCATION PC6804
J 0
(-1000 3300);
DISPLAY 0.489362 (-1000 3300);
PAINT SKYBLUE (-1000 3300);
FORCEPROP 0 LAST $SEC 1
J 0
(-1000 3325);
DISPLAY 0.680851 (-1000 3325);
PAINT MONO (-1000 3325);
DISPLAY INVISIBLE (-1000 3325);
FORCEPROP 0 LAST CDS_SEC 1
J 0
(-1000 3325);
DISPLAY 0.680851 (-1000 3325);
DISPLAY INVISIBLE (-1000 3325);
FORCEPROP 1 LASTPIN (-1050 3300) $PN 1
J 0
(-1040 3285);
DISPLAY 0.787234 (-1040 3285);
PAINT MONO (-1040 3285);
FORCEPROP 1 LASTPIN (-1050 3100) $PN 2
J 0
(-1040 3085);
DISPLAY 0.787234 (-1040 3085);
PAINT MONO (-1040 3085);
FORCEPROP 1 LAST PACK_TYPE SMLF
J 0
(-1000 3050);
DISPLAY 0.489362 (-1000 3050);
PAINT SKYBLUE (-1000 3050);
FORCEPROP 1 LAST VOLTAGE 2.5V
J 0
(-1000 3150);
DISPLAY 0.489362 (-1000 3150);
PAINT SKYBLUE (-1000 3150);
FORCEPROP 1 LAST VALUE 390UF
J 0
(-1000 3250);
DISPLAY 0.489362 (-1000 3250);
PAINT SKYBLUE (-1000 3250);
FORCEPROP 1 LAST MATERIAL ALUM
J 0
(-1000 3100);
DISPLAY 0.489362 (-1000 3100);
PAINT SKYBLUE (-1000 3100);
FORCEPROP 1 LAST TOLERANCE 20%
J 0
(-1000 3200);
DISPLAY 0.489362 (-1000 3200);
PAINT SKYBLUE (-1000 3200);
FORCEPROP 2 LAST CDS_LIB pure_quanta
J 0
(-1050 3200);
DISPLAY INVISIBLE (-1050 3200);
FORCEPROP 1 LAST PATH I47
J 0
(-1000 3350);
DISPLAY 0.978723 (-1000 3350);
DISPLAY INVISIBLE (-1000 3350);
FORCEPROP 1 LAST PART_NUMBER CC7390JMZ13
J 0
(-1000 3000);
DISPLAY 0.489362 (-1000 3000);
PAINT SKYBLUE (-1000 3000);
DISPLAY INVISIBLE (-1000 3000);
FORCEADD UNIVERSAL_GND..1
(-1025 2825);
FORCEPROP 3 LASTPIN (-1025 2875) SIG_NAME GND\g
J 0
(-1015 2885);
DISPLAY 0.659574 (-1015 2885);
PAINT MONO (-1015 2885);
DISPLAY INVISIBLE (-1015 2885);
FORCEPROP 2 LAST CDS_LIB pure_quanta_power
J 0
(-1025 2825);
DISPLAY INVISIBLE (-1025 2825);
FORCEPROP 1 LAST HDL_POWER GND
J 1
(-1000 2750);
DISPLAY 0.872340 (-1000 2750);
PAINT GREEN (-1000 2750);
DISPLAY INVISIBLE (-1000 2750);
FORCEPROP 1 LAST PATH I48
J 0
(-950 2825);
DISPLAY 0.872340 (-950 2825);
PAINT AQUA (-950 2825);
DISPLAY INVISIBLE (-950 2825);
FORCEADD Q_CAP..1
(-750 3200);
FORCEPROP 1 LAST LOCATION PC6533
J 0
(-700 3300);
DISPLAY 0.489362 (-700 3300);
PAINT SKYBLUE (-700 3300);
FORCEPROP 2 LAST SEC 1
J 0
(-698 3407);
DISPLAY 0.680851 (-698 3407);
PAINT MONO (-698 3407);
DISPLAY INVISIBLE (-698 3407);
FORCEPROP 1 LASTPIN (-750 3300) $PN 1
J 0
(-740 3280);
DISPLAY 0.489362 (-740 3280);
FORCEPROP 1 LASTPIN (-750 3100) $PN 2
J 0
(-740 3080);
DISPLAY 0.489362 (-740 3080);
FORCEPROP 1 LAST MATERIAL X7R
J 0
(-700 3100);
DISPLAY 0.489362 (-700 3100);
PAINT SKYBLUE (-700 3100);
FORCEPROP 1 LAST TOLERANCE 10%
J 0
(-700 3150);
DISPLAY 0.489362 (-700 3150);
PAINT SKYBLUE (-700 3150);
FORCEPROP 1 LAST PACK_TYPE 0402
J 0
(-700 3000);
DISPLAY 0.489362 (-700 3000);
PAINT SKYBLUE (-700 3000);
FORCEPROP 1 LAST VALUE 0.1UF
J 0
(-700 3250);
DISPLAY 0.489362 (-700 3250);
PAINT SKYBLUE (-700 3250);
FORCEPROP 1 LAST VOLTAGE 25V
J 0
(-700 3200);
DISPLAY 0.489362 (-700 3200);
PAINT SKYBLUE (-700 3200);
FORCEPROP 2 LAST CDS_LIB pure_quanta
J 0
(-750 3200);
PAINT MONO (-750 3200);
DISPLAY INVISIBLE (-750 3200);
FORCEPROP 2 LAST SEC_TYPE 0402
J 0
(-700 3396);
DISPLAY 1.021277 (-700 3396);
DISPLAY INVISIBLE (-700 3396);
FORCEPROP 1 LAST PATH I49
J 0
(-700 3350);
DISPLAY 0.978723 (-700 3350);
PAINT WHITE (-700 3350);
DISPLAY INVISIBLE (-700 3350);
FORCEPROP 1 LAST PART_NUMBER CH4104K1B00
J 0
(-700 3050);
DISPLAY 0.489362 (-700 3050);
PAINT SKYBLUE (-700 3050);
DISPLAY INVISIBLE (-700 3050);
FORCEADD Q_CAP..1
R 2
(-8500 3250);
FORCEPROP 1 LAST LOCATION C105
J 2
(-8550 3350);
DISPLAY 0.489362 (-8550 3350);
PAINT SKYBLUE (-8550 3350);
FORCEPROP 0 LAST $SEC 1
J 0
(-8550 3400);
DISPLAY 0.680851 (-8550 3400);
PAINT MONO (-8550 3400);
DISPLAY INVISIBLE (-8550 3400);
FORCEPROP 0 LAST CDS_SEC 1
J 0
(-8550 3400);
DISPLAY 0.680851 (-8550 3400);
DISPLAY INVISIBLE (-8550 3400);
FORCEPROP 1 LASTPIN (-8500 3350) $PN 1
J 2
(-8510 3330);
DISPLAY 0.489362 (-8510 3330);
PAINT MONO (-8510 3330);
FORCEPROP 1 LASTPIN (-8500 3150) $PN 2
J 2
(-8510 3130);
DISPLAY 0.489362 (-8510 3130);
PAINT MONO (-8510 3130);
FORCEPROP 1 LAST PACK_TYPE 0402
J 2
(-8550 3050);
DISPLAY 0.489362 (-8550 3050);
PAINT SKYBLUE (-8550 3050);
FORCEPROP 1 LAST MATERIAL EMPTY
J 2
(-8550 3150);
DISPLAY 0.489362 (-8550 3150);
PAINT RED (-8550 3150);
FORCEPROP 1 LAST TOLERANCE 10%
J 2
(-8550 3200);
DISPLAY 0.489362 (-8550 3200);
PAINT SKYBLUE (-8550 3200);
FORCEPROP 1 LAST VOLTAGE 25V
J 2
(-8550 3250);
DISPLAY 0.489362 (-8550 3250);
PAINT SKYBLUE (-8550 3250);
FORCEPROP 1 LAST VALUE 0.1UF
J 2
(-8550 3300);
DISPLAY 0.489362 (-8550 3300);
PAINT SKYBLUE (-8550 3300);
FORCEPROP 2 LAST CDS_LIB pure_quanta
J 0
(-8500 3250);
DISPLAY INVISIBLE (-8500 3250);
FORCEPROP 1 LAST PATH I5
J 2
(-8550 3400);
DISPLAY 0.978723 (-8550 3400);
PAINT WHITE (-8550 3400);
DISPLAY INVISIBLE (-8550 3400);
FORCEPROP 1 LAST PART_NUMBER CH4104K1B00
J 2
(-8575 3100);
DISPLAY 0.489362 (-8575 3100);
PAINT SKYBLUE (-8575 3100);
DISPLAY INVISIBLE (-8575 3100);
FORCEADD P1V0..1
(-425 3825);
FORCEPROP 3 LASTPIN (-425 3775) SIG_NAME P1V8_CPU1_RT_1D\g
J 0
(-415 3785);
DISPLAY 0.659574 (-415 3785);
PAINT MONO (-415 3785);
DISPLAY INVISIBLE (-415 3785);
FORCEPROP 1 LAST HDL_POWER P1V8_CPU1_RT_1D
J 1
(-425 3875);
DISPLAY 0.489362 (-425 3875);
PAINT SKYBLUE (-425 3875);
FORCEPROP 2 LAST CDS_LIB pure_quanta_power
J 0
(-425 3825);
PAINT MONO (-425 3825);
DISPLAY INVISIBLE (-425 3825);
FORCEPROP 1 LAST PATH I50
J 0
(-375 3850);
DISPLAY 0.872340 (-375 3850);
PAINT AQUA (-375 3850);
DISPLAY INVISIBLE (-375 3850);
FORCEADD MPQ8633BGLEC838Z..1
(-5675 3275);
FORCEPROP 1 LAST LOCATION PU6501
J 0
(-5922 4182);
DISPLAY 0.489362 (-5922 4182);
PAINT SKYBLUE (-5922 4182);
FORCEPROP 0 LAST $SEC 1
J 0
(-5925 4350);
DISPLAY 0.680851 (-5925 4350);
PAINT MONO (-5925 4350);
DISPLAY INVISIBLE (-5925 4350);
FORCEPROP 0 LAST CDS_SEC 1
J 0
(-5925 4350);
DISPLAY 1.021277 (-5925 4350);
DISPLAY INVISIBLE (-5925 4350);
FORCEPROP 0 LASTPIN (-5275 2600) $PN 2
J 0
(-5265 2610);
DISPLAY 0.489362 (-5265 2610);
PAINT MONO (-5265 2610);
FORCEPROP 0 LASTPIN (-5275 3750) $PN 1
J 0
(-5265 3760);
DISPLAY 0.489362 (-5265 3760);
PAINT MONO (-5265 3760);
FORCEPROP 0 LASTPIN (-6075 2650) $PN 3
J 2
(-6085 2660);
DISPLAY 0.489362 (-6085 2660);
PAINT MONO (-6085 2660);
FORCEPROP 0 LASTPIN (-6075 3450) $PN 8
J 2
(-6085 3460);
DISPLAY 0.489362 (-6085 3460);
PAINT MONO (-6085 3460);
FORCEPROP 0 LASTPIN (-5275 3000) $PN 7
J 0
(-5265 3010);
DISPLAY 0.489362 (-5265 3010);
PAINT MONO (-5265 3010);
FORCEPROP 0 LASTPIN (-6075 3250) $PN 4
J 2
(-6085 3260);
DISPLAY 0.489362 (-6085 3260);
PAINT MONO (-6085 3260);
FORCEPROP 0 LASTPIN (-5275 2650) $PN 11_18
J 0
(-5265 2660);
DISPLAY 0.489362 (-5265 2660);
PAINT MONO (-5265 2660);
FORCEPROP 0 LASTPIN (-5275 3950) $PN 9
J 0
(-5265 3960);
DISPLAY 0.489362 (-5265 3960);
PAINT MONO (-5265 3960);
FORCEPROP 0 LASTPIN (-5275 2850) $PN 6
J 0
(-5265 2860);
DISPLAY 0.489362 (-5265 2860);
PAINT MONO (-5265 2860);
FORCEPROP 0 LASTPIN (-5275 3450) $PN 20
J 0
(-5265 3460);
DISPLAY 0.489362 (-5265 3460);
PAINT MONO (-5265 3460);
FORCEPROP 0 LASTPIN (-5275 2750) $PN 5
J 0
(-5265 2760);
DISPLAY 0.489362 (-5265 2760);
PAINT MONO (-5265 2760);
FORCEPROP 0 LASTPIN (-6075 3000) $PN 19
J 2
(-6085 3010);
DISPLAY 0.489362 (-6085 3010);
PAINT MONO (-6085 3010);
FORCEPROP 0 LASTPIN (-6075 3950) $PN 10
J 2
(-6085 3960);
DISPLAY 0.489362 (-6085 3960);
PAINT MONO (-6085 3960);
FORCEPROP 0 LASTPIN (-6075 3900) $PN 21
J 2
(-6085 3910);
DISPLAY 0.489362 (-6085 3910);
PAINT MONO (-6085 3910);
FORCEPROP 2 LAST VALUE MPQ8633BGLE-C838-Z
J 0
(-5925 4250);
DISPLAY 0.489362 (-5925 4250);
PAINT SKYBLUE (-5925 4250);
FORCEPROP 2 LAST PART_TYPE SMLF
J 0
(-5925 4300);
DISPLAY 0.680851 (-5925 4300);
FORCEPROP 1 LAST MATERIAL IC
J 0
(-5922 4004);
DISPLAY 0.489362 (-5922 4004);
PAINT SKYBLUE (-5922 4004);
FORCEPROP 1 LAST CDS_LMAN_SYM_OUTLINE -250,725,250,-725
J 0
(-5675 3275);
DISPLAY 0.468085 (-5675 3275);
PAINT GREEN (-5675 3275);
DISPLAY INVISIBLE (-5675 3275);
FORCEPROP 1 LAST NEEDS_NO_SIZE TRUE
J 0
(-5675 3275);
DISPLAY 0.723404 (-5675 3275);
PAINT GREEN (-5675 3275);
DISPLAY INVISIBLE (-5675 3275);
FORCEPROP 2 LAST CDS_LIB pure_quanta
J 0
(-5675 3275);
DISPLAY INVISIBLE (-5675 3275);
FORCEPROP 1 LAST PATH I51
J 0
(-5675 3275);
DISPLAY 0.723404 (-5675 3275);
PAINT GREEN (-5675 3275);
DISPLAY INVISIBLE (-5675 3275);
FORCEPROP 1 LAST PART_NUMBER AL008633005
J 0
(-5922 4083);
DISPLAY 0.489362 (-5922 4083);
PAINT SKYBLUE (-5922 4083);
DISPLAY INVISIBLE (-5922 4083);
FORCEADD Q_CAP..1
(-6525 4000);
FORCEPROP 1 LAST LOCATION PC6905
J 0
(-6475 4100);
DISPLAY 0.510638 (-6475 4100);
FORCEPROP 0 LAST $SEC 1
J 0
(-6475 4125);
DISPLAY 0.680851 (-6475 4125);
PAINT MONO (-6475 4125);
DISPLAY INVISIBLE (-6475 4125);
FORCEPROP 0 LAST CDS_SEC 1
J 0
(-6475 4125);
DISPLAY 0.680851 (-6475 4125);
DISPLAY INVISIBLE (-6475 4125);
FORCEPROP 1 LASTPIN (-6525 4100) $PN 1
J 0
(-6515 4080);
DISPLAY 0.787234 (-6515 4080);
PAINT MONO (-6515 4080);
FORCEPROP 1 LASTPIN (-6525 3900) $PN 2
J 0
(-6515 3880);
DISPLAY 0.787234 (-6515 3880);
PAINT MONO (-6515 3880);
FORCEPROP 1 LAST TOLERANCE 20%
J 0
(-6475 3950);
DISPLAY 0.510638 (-6475 3950);
FORCEPROP 1 LAST VALUE 22UF
J 0
(-6475 4050);
DISPLAY 0.510638 (-6475 4050);
FORCEPROP 1 LAST VOLTAGE 16V
J 0
(-6475 4000);
DISPLAY 0.510638 (-6475 4000);
FORCEPROP 1 LAST MATERIAL X6S
J 0
(-6475 3900);
DISPLAY 0.510638 (-6475 3900);
FORCEPROP 1 LAST PACK_TYPE C0805
J 0
(-6475 3800);
DISPLAY 0.510638 (-6475 3800);
FORCEPROP 2 LAST CDS_LIB pure_quanta
J 0
(-6525 4000);
DISPLAY INVISIBLE (-6525 4000);
FORCEPROP 1 LAST PATH I55
J 0
(-6475 4150);
DISPLAY 0.978723 (-6475 4150);
PAINT WHITE (-6475 4150);
DISPLAY INVISIBLE (-6475 4150);
FORCEPROP 1 LAST PART_NUMBER CH6223MEA01
J 0
(-6475 3850);
DISPLAY 0.510638 (-6475 3850);
DISPLAY INVISIBLE (-6475 3850);
FORCEADD Q_CAP..1
(-6700 4000);
FORCEPROP 1 LAST LOCATION PC6904
J 0
(-6650 4100);
DISPLAY 0.510638 (-6650 4100);
FORCEPROP 0 LAST $SEC 1
J 0
(-6650 4125);
DISPLAY 0.680851 (-6650 4125);
PAINT MONO (-6650 4125);
DISPLAY INVISIBLE (-6650 4125);
FORCEPROP 0 LAST CDS_SEC 1
J 0
(-6650 4125);
DISPLAY 0.680851 (-6650 4125);
DISPLAY INVISIBLE (-6650 4125);
FORCEPROP 1 LASTPIN (-6700 4100) $PN 1
J 0
(-6690 4080);
DISPLAY 0.787234 (-6690 4080);
PAINT MONO (-6690 4080);
FORCEPROP 1 LASTPIN (-6700 3900) $PN 2
J 0
(-6690 3880);
DISPLAY 0.787234 (-6690 3880);
PAINT MONO (-6690 3880);
FORCEPROP 1 LAST VOLTAGE 16V
J 0
(-6650 4000);
DISPLAY 0.510638 (-6650 4000);
FORCEPROP 1 LAST VALUE 22UF
J 0
(-6650 4050);
DISPLAY 0.510638 (-6650 4050);
FORCEPROP 1 LAST TOLERANCE 20%
J 0
(-6650 3950);
DISPLAY 0.510638 (-6650 3950);
FORCEPROP 1 LAST MATERIAL X6S
J 0
(-6650 3900);
DISPLAY 0.510638 (-6650 3900);
FORCEPROP 1 LAST PACK_TYPE C0805
J 0
(-6650 3800);
DISPLAY 0.510638 (-6650 3800);
FORCEPROP 2 LAST CDS_LIB pure_quanta
J 0
(-6700 4000);
DISPLAY INVISIBLE (-6700 4000);
FORCEPROP 1 LAST PATH I56
J 0
(-6650 4150);
DISPLAY 0.978723 (-6650 4150);
PAINT WHITE (-6650 4150);
DISPLAY INVISIBLE (-6650 4150);
FORCEPROP 1 LAST PART_NUMBER CH6223MEA01
J 0
(-6650 3850);
DISPLAY 0.510638 (-6650 3850);
DISPLAY INVISIBLE (-6650 3850);
FORCEADD Q_CAP..1
(-6900 4000);
FORCEPROP 1 LAST LOCATION PC6903
J 0
(-6850 4100);
DISPLAY 0.510638 (-6850 4100);
FORCEPROP 0 LAST $SEC 1
J 0
(-6850 4125);
DISPLAY 0.680851 (-6850 4125);
PAINT MONO (-6850 4125);
DISPLAY INVISIBLE (-6850 4125);
FORCEPROP 0 LAST CDS_SEC 1
J 0
(-6850 4125);
DISPLAY 0.680851 (-6850 4125);
DISPLAY INVISIBLE (-6850 4125);
FORCEPROP 1 LASTPIN (-6900 4100) $PN 1
J 0
(-6890 4080);
DISPLAY 0.787234 (-6890 4080);
PAINT MONO (-6890 4080);
FORCEPROP 1 LASTPIN (-6900 3900) $PN 2
J 0
(-6890 3880);
DISPLAY 0.787234 (-6890 3880);
PAINT MONO (-6890 3880);
FORCEPROP 1 LAST PACK_TYPE C0805
J 0
(-6850 3800);
DISPLAY 0.510638 (-6850 3800);
FORCEPROP 1 LAST MATERIAL X6S
J 0
(-6850 3900);
DISPLAY 0.510638 (-6850 3900);
FORCEPROP 1 LAST TOLERANCE 20%
J 0
(-6850 3950);
DISPLAY 0.510638 (-6850 3950);
FORCEPROP 1 LAST VOLTAGE 16V
J 0
(-6850 4000);
DISPLAY 0.510638 (-6850 4000);
FORCEPROP 1 LAST VALUE 22UF
J 0
(-6850 4050);
DISPLAY 0.510638 (-6850 4050);
FORCEPROP 2 LAST CDS_LIB pure_quanta
J 0
(-6900 4000);
DISPLAY INVISIBLE (-6900 4000);
FORCEPROP 1 LAST PATH I57
J 0
(-6850 4150);
DISPLAY 0.978723 (-6850 4150);
PAINT WHITE (-6850 4150);
DISPLAY INVISIBLE (-6850 4150);
FORCEPROP 1 LAST PART_NUMBER CH6223MEA01
J 0
(-6850 3850);
DISPLAY 0.510638 (-6850 3850);
DISPLAY INVISIBLE (-6850 3850);
FORCEADD Q_CAPP..1
R 2
(-8525 4000);
FORCEPROP 1 LAST LOCATION PC6801
J 2
(-8575 4100);
DISPLAY 0.787234 (-8575 4100);
FORCEPROP 0 LAST $SEC 1
J 2
(-8575 4150);
DISPLAY 0.680851 (-8575 4150);
PAINT MONO (-8575 4150);
DISPLAY INVISIBLE (-8575 4150);
FORCEPROP 0 LAST CDS_SEC 1
J 2
(-8575 4150);
DISPLAY 0.680851 (-8575 4150);
DISPLAY INVISIBLE (-8575 4150);
FORCEPROP 1 LASTPIN (-8525 4100) $PN 1
J 2
(-8535 4085);
DISPLAY 0.787234 (-8535 4085);
PAINT MONO (-8535 4085);
FORCEPROP 1 LASTPIN (-8525 3900) $PN 2
J 2
(-8535 3885);
DISPLAY 0.787234 (-8535 3885);
PAINT MONO (-8535 3885);
FORCEPROP 1 LAST PACK_TYPE SMLF
J 2
(-8575 3850);
DISPLAY 0.510638 (-8575 3850);
FORCEPROP 1 LAST VOLTAGE 16V
J 2
(-8575 3950);
DISPLAY 0.510638 (-8575 3950);
FORCEPROP 1 LAST TOLERANCE 20%
J 2
(-8575 4000);
DISPLAY 0.510638 (-8575 4000);
FORCEPROP 1 LAST MATERIAL OSCON
J 2
(-8575 3900);
DISPLAY 0.510638 (-8575 3900);
FORCEPROP 1 LAST VALUE 270UF
J 2
(-8575 4050);
DISPLAY 0.510638 (-8575 4050);
FORCEPROP 2 LAST CDS_LIB pure_quanta
J 2
(-8525 4000);
DISPLAY INVISIBLE (-8525 4000);
FORCEPROP 1 LAST PATH I6
J 2
(-8575 4150);
DISPLAY 0.978723 (-8575 4150);
DISPLAY INVISIBLE (-8575 4150);
FORCEPROP 1 LAST PART_NUMBER CC72703MZ11
J 2
(-8575 3800);
DISPLAY 0.510638 (-8575 3800);
DISPLAY INVISIBLE (-8575 3800);
FORCEADD Q_CAP..1
(-8400 4000);
FORCEPROP 1 LAST LOCATION PC6803
J 0
(-8350 4100);
DISPLAY 0.489362 (-8350 4100);
PAINT SKYBLUE (-8350 4100);
FORCEPROP 0 LAST $SEC 1
J 0
(-8350 4125);
DISPLAY 0.680851 (-8350 4125);
PAINT MONO (-8350 4125);
DISPLAY INVISIBLE (-8350 4125);
FORCEPROP 0 LAST CDS_SEC 1
J 0
(-8350 4125);
DISPLAY 0.680851 (-8350 4125);
DISPLAY INVISIBLE (-8350 4125);
FORCEPROP 1 LASTPIN (-8400 4100) $PN 1
J 0
(-8390 4080);
DISPLAY 0.787234 (-8390 4080);
PAINT MONO (-8390 4080);
FORCEPROP 1 LASTPIN (-8400 3900) $PN 2
J 0
(-8390 3880);
DISPLAY 0.787234 (-8390 3880);
PAINT MONO (-8390 3880);
FORCEPROP 1 LAST VOLTAGE 16V
J 0
(-8350 4000);
DISPLAY 0.489362 (-8350 4000);
PAINT SKYBLUE (-8350 4000);
FORCEPROP 1 LAST VALUE 22UF
J 0
(-8350 4050);
DISPLAY 0.489362 (-8350 4050);
PAINT SKYBLUE (-8350 4050);
FORCEPROP 1 LAST PACK_TYPE C0805
J 0
(-8350 3800);
DISPLAY 0.489362 (-8350 3800);
PAINT SKYBLUE (-8350 3800);
FORCEPROP 1 LAST MATERIAL X6S
J 0
(-8350 3900);
DISPLAY 0.489362 (-8350 3900);
PAINT SKYBLUE (-8350 3900);
FORCEPROP 1 LAST TOLERANCE 20%
J 0
(-8350 3950);
DISPLAY 0.489362 (-8350 3950);
PAINT SKYBLUE (-8350 3950);
FORCEPROP 2 LAST CDS_LIB pure_quanta
J 0
(-8400 4000);
DISPLAY INVISIBLE (-8400 4000);
FORCEPROP 1 LAST PATH I7
J 0
(-8350 4150);
DISPLAY 0.978723 (-8350 4150);
PAINT WHITE (-8350 4150);
DISPLAY INVISIBLE (-8350 4150);
FORCEPROP 1 LAST PART_NUMBER CH6223MEA01
J 0
(-8350 3850);
DISPLAY 0.489362 (-8350 3850);
PAINT SKYBLUE (-8350 3850);
DISPLAY INVISIBLE (-8350 3850);
FORCEADD P1V0_AUX..1
(-9150 4425);
FORCEPROP 3 LASTPIN (-9150 4375) SIG_NAME P12V_AUX\g
J 0
(-9140 4385);
DISPLAY 0.659574 (-9140 4385);
PAINT MONO (-9140 4385);
DISPLAY INVISIBLE (-9140 4385);
FORCEPROP 1 LAST HDL_POWER P12V_AUX
J 1
(-9139 4472);
DISPLAY 0.489362 (-9139 4472);
PAINT GREEN (-9139 4472);
FORCEPROP 2 LAST CDS_LIB mstr_symbols
J 0
(-9150 4425);
DISPLAY INVISIBLE (-9150 4425);
FORCEPROP 1 LAST VOLTAGE 1.0V
J 0
(-9195 4382);
DISPLAY 0.340426 (-9195 4382);
PAINT SKYBLUE (-9195 4382);
DISPLAY INVISIBLE (-9195 4382);
FORCEPROP 2 LAST ROOM VR_DDR1_POWER_STAGE
J 0
(-9150 4525);
DISPLAY 0.978723 (-9150 4525);
PAINT RED (-9150 4525);
DISPLAY INVISIBLE (-9150 4525);
FORCEPROP 1 LAST BODY_TYPE PLUMBING
J 0
(-9195 4382);
DISPLAY 0.340426 (-9195 4382);
PAINT GREEN (-9195 4382);
DISPLAY INVISIBLE (-9195 4382);
FORCEPROP 1 LAST PATH I8
J 0
(-9100 4450);
DISPLAY 0.872340 (-9100 4450);
PAINT AQUA (-9100 4450);
DISPLAY INVISIBLE (-9100 4450);
FORCEADD Q_INDUCTOR..1
(-8800 4250);
FORCEPROP 1 LAST LOCATION PL6503
J 0
(-8925 4410);
DISPLAY 0.489362 (-8925 4410);
PAINT SKYBLUE (-8925 4410);
FORCEPROP 0 LAST $SEC 1
J 0
(-8925 4525);
DISPLAY 0.680851 (-8925 4525);
PAINT MONO (-8925 4525);
DISPLAY INVISIBLE (-8925 4525);
FORCEPROP 0 LAST CDS_SEC 1
J 0
(-8925 4525);
DISPLAY 0.680851 (-8925 4525);
DISPLAY INVISIBLE (-8925 4525);
FORCEPROP 0 LASTPIN (-8900 4225) $PN 1
J 2
(-8910 4235);
DISPLAY 0.680851 (-8910 4235);
PAINT MONO (-8910 4235);
FORCEPROP 0 LASTPIN (-8700 4225) $PN 2
J 0
(-8690 4235);
DISPLAY 0.680851 (-8690 4235);
PAINT MONO (-8690 4235);
FORCEPROP 2 LAST VALUE 100NH/16A
J 0
(-8925 4500);
DISPLAY 0.489362 (-8925 4500);
PAINT SKYBLUE (-8925 4500);
FORCEPROP 2 LAST PACK_TYPE SMLF
J 0
(-8925 4450);
DISPLAY 0.489362 (-8925 4450);
PAINT SKYBLUE (-8925 4450);
FORCEPROP 1 LAST MATERIAL IND
J 0
(-8925 4305);
DISPLAY 0.489362 (-8925 4305);
PAINT SKYBLUE (-8925 4305);
FORCEPROP 2 LAST CDS_LIB pure_quanta
J 0
(-8800 4250);
DISPLAY INVISIBLE (-8800 4250);
FORCEPROP 1 LAST NEEDS_NO_SIZE TRUE
J 0
(-8800 4250);
DISPLAY 0.468085 (-8800 4250);
PAINT GREEN (-8800 4250);
DISPLAY INVISIBLE (-8800 4250);
FORCEPROP 1 LAST PATH I9
J 0
(-8725 4305);
DISPLAY 0.723404 (-8725 4305);
PAINT GREEN (-8725 4305);
DISPLAY INVISIBLE (-8725 4305);
FORCEPROP 1 LAST PART_NUMBER CV+10G0MZ04
J 0
(-8925 4360);
DISPLAY 0.489362 (-8925 4360);
PAINT SKYBLUE (-8925 4360);
DISPLAY INVISIBLE (-8925 4360);
FORCEADD DNS..1
(-8525 3150);
PAINT RED (-8525 3150);
FORCEPROP 2 LAST CDS_LIB mstr_misc
J 0
(-8525 3150);
DISPLAY INVISIBLE (-8525 3150);
FORCEPROP 1 LAST COMMENT_BODY TRUE
J 0
(-8525 3150);
DISPLAY INVISIBLE (-8525 3150);
FORCEADD QUANTA_TITLE_BLOCK_C..1
(0 0);
FORCEPROP 0 LAST CDS_CON_LAST_MODIFIED Thu Sep 14 16:13:01 2023
J 0
(-1885 15);
DISPLAY INVISIBLE (-1885 15);
FORCEPROP 1 LAST CUSTOM_TXT_CDS <CON_LAST_MODIFIED>
J 0
(-1885 15);
DISPLAY 0.978723 (-1885 15);
FORCEPROP 2 LAST CUSTOM_TXT_CDS <XR_PAGE_TITLE>
J 0
(-7890 5250);
DISPLAY 0.638298 (-7890 5250);
PAINT PINK (-7890 5250);
DISPLAY INVISIBLE (-7890 5250);
FORCEPROP 1 LAST CUSTOM_TXT_CDS <NAME_2>
J 0
(-3175 50);
FORCEPROP 1 LAST CUSTOM_TXT_CDS <NAME_1>
J 0
(-3175 175);
FORCEPROP 1 LAST CUSTOM_TXT_CDS <Q_NUMBER>
J 0
(-1403 103);
DISPLAY 1.212766 (-1403 103);
FORCEPROP 1 LAST CUSTOM_TXT_CDS <Q_PROJ>
J 0
(-2382 102);
DISPLAY 1.212766 (-2382 102);
FORCEPROP 1 LAST CUSTOM_TXT_CDS <Q_REV>
J 0
(-184 103);
DISPLAY 1.212766 (-184 103);
FORCEPROP 1 LAST CUSTOM_TXT_CDS <CON_PAGE_NUM> OF <CON_TOTAL_PAGES>
J 0
(-446 18);
DISPLAY 0.978723 (-446 18);
FORCEPROP 1 LAST Q_TITLE P1V8_CPU1_RT_1D
J 0
(-9366 26);
DISPLAY 2.446809 (-9366 26);
PAINT GREEN (-9366 26);
FORCEPROP 2 LAST CDS_XR_PAGE_TITLE CR-362 : @T6G_MB_LIB.T6G(SCH_1):PAGE362
J 0
(-7890 5250);
DISPLAY 0.638298 (-7890 5250);
PAINT PINK (-7890 5250);
DISPLAY INVISIBLE (-7890 5250);
FORCEPROP 2 LAST CDS_LIB pure_quanta
J 0
(0 0);
DISPLAY INVISIBLE (0 0);
FORCEPROP 1 LAST CDS_LMAN_SYM_OUTLINE -9475,6775,100,-125
J 0
(0 0);
DISPLAY 0.468085 (0 0);
PAINT GREEN (0 0);
DISPLAY INVISIBLE (0 0);
FORCEPROP 2 LAST PAGE_BORDER TRUE
J 0
(-7890 5250);
DISPLAY 0.638298 (-7890 5250);
PAINT PINK (-7890 5250);
DISPLAY INVISIBLE (-7890 5250);
FORCEPROP 1 LAST Q_DEPT BU9
J 1
(-3763 49);
DISPLAY 1.957447 (-3763 49);
PAINT GREEN (-3763 49);
DISPLAY INVISIBLE (-3763 49);
FORCEPROP 1 LAST COMMENT_BODY TRUE
J 0
(12 -13);
DISPLAY 0.978723 (12 -13);
PAINT GREEN (12 -13);
DISPLAY INVISIBLE (12 -13);
WIRE 16 -1 (-7975 3250)(-7100 3250);
WIRE 16 -1 (-7975 3250)(-7975 2850);
WIRE 16 -1 (-7500 2250)(-7500 2325);
WIRE 16 -1 (-7500 3000)(-7500 2950);
WIRE 16 -1 (-6625 2325)(-6625 2225);
WIRE 16 -1 (-9150 3925)(-9150 3750);
WIRE 16 -1 (-4925 2375)(-4925 2475);
WIRE 16 -1 (-5275 2850)(-4550 2850);
WIRE 16 -1 (-4550 2850)(-4550 2375);
WIRE 16 -1 (-4625 4475)(-4625 4350);
WIRE 16 -1 (-4075 2375)(-4075 2250);
WIRE 16 -1 (-8500 3100)(-8500 3150);
WIRE 16 -1 (-2775 3700)(-2775 3650);
WIRE 17 273 (-9100 1250)(-6925 1250);
WIRE 17 273 (-9100 1725)(-9100 1250);
WIRE 17 273 (-6925 1725)(-6925 1250);
WIRE 17 273 (-9100 1725)(-6925 1725);
WIRE 16 -1 (-6625 2525)(-6625 2650);
FORCEPROP 2 LAST SIG_NAME P1V8_RETIMER_CPU1_CS
J 0
(-6660 2675);
DISPLAY 0.489362 (-6660 2675);
PAINT SKYBLUE (-6660 2675);
FORCEPROP 2 LASTPROP $XRERR UNIQUE?
J 0
(-6900 2675);
DISPLAY 0.638298 (-6900 2675);
PAINT MONO (-6900 2675);
DISPLAY INVISIBLE (-6900 2675);
WIRE 16 -1 (-6625 2650)(-6075 2650);
WIRE 16 -1 (-3925 3450)(-3600 3450);
WIRE 16 -1 (-3925 3525)(-3925 3450);
WIRE 16 -1 (-5275 3450)(-3925 3450);
FORCEPROP 2 LAST SIG_NAME SW_P1V8_RETIMER_CPU1_SW
J 0
(-5170 3467);
DISPLAY 0.489362 (-5170 3467);
PAINT SKYBLUE (-5170 3467);
FORCEPROP 2 LASTPROP $XRERR UNIQUE?
J 0
(-5410 3467);
DISPLAY 0.638298 (-5410 3467);
PAINT MONO (-5410 3467);
DISPLAY INVISIBLE (-5410 3467);
WIRE 16 -1 (-5275 3950)(-4625 3950);
WIRE 16 -1 (-4625 3950)(-3675 3950);
FORCEPROP 2 LAST SIG_NAME PWRGD_P1V8_RETIMER_CPU1
J 0
(-4410 3975);
DISPLAY 0.489362 (-4410 3975);
PAINT SKYBLUE (-4410 3975);
FORCEPROP 2 LASTPROP $XRERR UNIQUE?
J 0
(-4650 3975);
DISPLAY 0.638298 (-4650 3975);
PAINT MONO (-4650 3975);
DISPLAY INVISIBLE (-4650 3975);
WIRE 16 -1 (-4625 4150)(-4625 3950);
WIRE 17 273 (-275 6450)(-1850 6450);
WIRE 17 273 (-275 6450)(-275 5600);
WIRE 17 273 (-1850 6450)(-1850 5600);
WIRE 17 273 (-1850 5600)(-275 5600);
WIRE 16 -1 (-6525 3900)(-6525 3778);
WIRE 16 -1 (-6525 3778)(-6700 3778);
WIRE 16 -1 (-6700 3900)(-6700 3778);
WIRE 16 -1 (-6700 3778)(-6900 3778);
WIRE 16 -1 (-6900 3900)(-6900 3778);
WIRE 16 -1 (-6900 3778)(-7250 3778);
WIRE 16 -1 (-7250 3900)(-7250 3778);
WIRE 16 -1 (-7250 3778)(-7450 3778);
WIRE 16 -1 (-7450 3900)(-7450 3778);
WIRE 16 -1 (-7450 3778)(-7675 3778);
WIRE 16 -1 (-7675 3900)(-7675 3778);
WIRE 16 -1 (-7675 3778)(-7850 3778);
WIRE 16 -1 (-7850 3900)(-7850 3778);
WIRE 16 -1 (-7850 3778)(-7875 3778);
WIRE 16 -1 (-7875 3675)(-7875 3778);
WIRE 16 -1 (-7875 3778)(-8075 3778);
WIRE 16 -1 (-8075 3900)(-8075 3778);
WIRE 16 -1 (-8075 3778)(-8075 3775);
WIRE 16 -1 (-8075 3775)(-8400 3775);
WIRE 16 -1 (-8400 3900)(-8400 3775);
WIRE 16 -1 (-8525 3775)(-8400 3775);
WIRE 16 -1 (-8525 3900)(-8525 3775);
WIRE 16 -1 (-5050 2600)(-5050 2650);
WIRE 16 -1 (-5050 2375)(-5050 2600);
WIRE 16 -1 (-5275 2600)(-5050 2600);
WIRE 16 -1 (-5050 2650)(-5275 2650);
WIRE 16 -1 (-2850 3100)(-2850 2950);
WIRE 16 -1 (-2425 2950)(-2850 2950);
WIRE 16 -1 (-2425 3100)(-2425 2950);
WIRE 16 -1 (-2150 2950)(-2425 2950);
WIRE 16 -1 (-2150 2950)(-1900 2950);
WIRE 16 -1 (-2150 3100)(-2150 2950);
WIRE 16 -1 (-1900 3100)(-1900 2950);
WIRE 16 -1 (-1900 2950)(-1625 2950);
WIRE 16 -1 (-1625 3100)(-1625 2950);
WIRE 16 -1 (-1350 2950)(-1625 2950);
WIRE 16 -1 (-1350 2950)(-1350 3100);
WIRE 16 -1 (-1350 2950)(-1050 2950);
WIRE 16 -1 (-1050 3100)(-1050 2950);
WIRE 16 -1 (-1025 2950)(-1050 2950);
WIRE 16 -1 (-750 2950)(-1025 2950);
WIRE 16 -1 (-1025 2875)(-1025 2950);
WIRE 16 -1 (-750 2950)(-750 3100);
WIRE 16 -1 (-3400 3450)(-2850 3450);
WIRE 16 -1 (-2850 3450)(-2425 3450);
WIRE 16 -1 (-2850 3300)(-2850 3450);
WIRE 16 -1 (-2150 3450)(-2425 3450);
WIRE 16 -1 (-2425 3300)(-2425 3450);
WIRE 16 -1 (-2150 3450)(-1900 3450);
WIRE 16 -1 (-2150 3300)(-2150 3450);
WIRE 16 -1 (-1900 3450)(-1625 3450);
WIRE 16 -1 (-1900 3450)(-1900 3300);
WIRE 16 -1 (-1350 3450)(-1625 3450);
WIRE 16 -1 (-1625 3450)(-1625 3300);
WIRE 16 -1 (-1350 3450)(-1050 3450);
WIRE 16 -1 (-1350 3450)(-1350 3300);
WIRE 16 -1 (-1050 3450)(-750 3450);
WIRE 16 -1 (-1050 3300)(-1050 3450);
WIRE 16 -1 (-425 3450)(-750 3450);
WIRE 16 -1 (-750 3300)(-750 3450);
WIRE 16 -1 (-425 2650)(-425 3450);
WIRE 16 -1 (-425 3450)(-425 3775);
WIRE 16 -1 (-2950 2650)(-425 2650);
WIRE 16 -1 (-2950 3000)(-2950 2650);
WIRE 16 -1 (-3175 3000)(-2950 3000);
WIRE 16 -1 (-3175 3000)(-3175 2675);
WIRE 16 -1 (-3400 3000)(-3175 3000);
WIRE 16 -1 (-3175 2675)(-3400 2675);
WIRE 16 -1 (-8900 4225)(-9150 4225);
WIRE 16 -1 (-9150 4375)(-9150 4225);
WIRE 16 -1 (-9150 4225)(-9150 4125);
WIRE 16 -1 (-6250 3900)(-6075 3900);
WIRE 16 -1 (-6250 3950)(-6250 3900);
WIRE 16 -1 (-6250 4225)(-6250 3950);
WIRE 16 -1 (-6250 3950)(-6075 3950);
WIRE 16 -1 (-6250 4225)(-6525 4225);
WIRE 16 -1 (-6525 4100)(-6525 4225);
WIRE 16 -1 (-6525 4225)(-6700 4225);
WIRE 16 -1 (-6700 4100)(-6700 4225);
WIRE 16 -1 (-6700 4225)(-6900 4225);
WIRE 16 -1 (-6900 4100)(-6900 4225);
WIRE 16 -1 (-6900 4225)(-7250 4225);
WIRE 16 -1 (-7250 4100)(-7250 4225);
WIRE 16 -1 (-7250 4225)(-7450 4225);
WIRE 16 -1 (-7450 4100)(-7450 4225);
WIRE 16 -1 (-7450 4225)(-7675 4225);
WIRE 16 -1 (-7675 4100)(-7675 4225);
WIRE 16 -1 (-7675 4225)(-7850 4225);
FORCEPROP 2 LAST SIG_NAME SW_P12V_AUX_P1V8_RETIMER_CPU1_FLT
J 0
(-7687 4248);
DISPLAY 0.489362 (-7687 4248);
PAINT SKYBLUE (-7687 4248);
FORCEPROP 2 LASTPROP $XRERR UNIQUE?
J 0
(-7927 4248);
DISPLAY 0.638298 (-7927 4248);
PAINT MONO (-7927 4248);
DISPLAY INVISIBLE (-7927 4248);
WIRE 16 -1 (-7850 4100)(-7850 4225);
WIRE 16 -1 (-7850 4225)(-8075 4225);
WIRE 16 -1 (-8075 4100)(-8075 4225);
WIRE 16 -1 (-8075 4225)(-8400 4225);
WIRE 16 -1 (-8400 4100)(-8400 4225);
WIRE 16 -1 (-8525 4225)(-8400 4225);
WIRE 16 -1 (-8525 4100)(-8525 4225);
WIRE 16 -1 (-8700 4225)(-8525 4225);
WIRE 17 273 (-9100 575)(-6925 575);
WIRE 17 273 (-9100 1175)(-9100 575);
WIRE 17 273 (-6925 1175)(-6925 575);
WIRE 17 273 (-9100 1175)(-6925 1175);
WIRE 16 -1 (-3925 3750)(-3925 3725);
WIRE 16 -1 (-4425 3750)(-3925 3750);
FORCEPROP 2 LAST SIG_NAME SW_P1V8_RETIMER_CPU1_BST_R
J 0
(-4410 3760);
DISPLAY 0.382979 (-4410 3760);
PAINT SKYBLUE (-4410 3760);
FORCEPROP 2 LASTPROP $XRERR UNIQUE?
J 0
(-4650 3760);
DISPLAY 0.638298 (-4650 3760);
PAINT MONO (-4650 3760);
DISPLAY INVISIBLE (-4650 3760);
WIRE 16 -1 (-5275 3750)(-4625 3750);
FORCEPROP 2 LAST SIG_NAME SW_P1V8_RETIMER_CPU1_BST
J 0
(-5185 3760);
DISPLAY 0.489362 (-5185 3760);
PAINT SKYBLUE (-5185 3760);
FORCEPROP 2 LASTPROP $XRERR UNIQUE?
J 0
(-5425 3760);
DISPLAY 0.638298 (-5425 3760);
PAINT MONO (-5425 3760);
DISPLAY INVISIBLE (-5425 3760);
WIRE 16 -1 (-3600 2675)(-3800 2675);
WIRE 16 -1 (-3800 3000)(-3800 2675);
WIRE 16 -1 (-3600 3000)(-3800 3000);
WIRE 16 -1 (-3800 3000)(-4075 3000);
WIRE 16 -1 (-4075 2575)(-4075 3000);
WIRE 16 -1 (-5275 3000)(-4075 3000);
FORCEPROP 2 LAST SIG_NAME P1V8_RETIMER_CPU1_FB
J 0
(-5176 3014);
DISPLAY 0.489362 (-5176 3014);
PAINT SKYBLUE (-5176 3014);
FORCEPROP 2 LASTPROP $XRERR UNIQUE?
J 0
(-5416 3014);
DISPLAY 0.638298 (-5416 3014);
PAINT MONO (-5416 3014);
DISPLAY INVISIBLE (-5416 3014);
WIRE 16 -1 (-6900 3250)(-6075 3250);
FORCEPROP 2 LAST SIG_NAME P1V8_RETIMER_CPU1_MODE
J 0
(-6735 3260);
DISPLAY 0.489362 (-6735 3260);
PAINT SKYBLUE (-6735 3260);
FORCEPROP 2 LASTPROP $XRERR UNIQUE?
J 0
(-6975 3260);
DISPLAY 0.638298 (-6975 3260);
PAINT MONO (-6975 3260);
DISPLAY INVISIBLE (-6975 3260);
WIRE 16 -1 (-4925 2675)(-4925 2750);
WIRE 16 -1 (-4925 2750)(-5275 2750);
FORCEPROP 2 LAST SIG_NAME P1V8_RETIMER_CPU1_REF
J 0
(-5185 2760);
DISPLAY 0.489362 (-5185 2760);
PAINT SKYBLUE (-5185 2760);
FORCEPROP 2 LASTPROP $XRERR UNIQUE?
J 0
(-5425 2760);
DISPLAY 0.638298 (-5425 2760);
PAINT MONO (-5425 2760);
DISPLAY INVISIBLE (-5425 2760);
WIRE 16 -1 (-3532 2097)(-3532 2098);
WIRE 16 -1 (-2575 3950)(-2775 3950);
WIRE 16 -1 (-2775 3900)(-2775 3950);
WIRE 16 -1 (-2775 3950)(-3475 3950);
FORCEPROP 2 LAST SIG_NAME FM_PWRGD_P1V8_RETIMER_CPU1
J 0
(-3260 3975);
DISPLAY 0.489362 (-3260 3975);
PAINT SKYBLUE (-3260 3975);
WIRE 16 -1 (-7500 2525)(-7500 2650);
WIRE 16 -1 (-7500 2650)(-6950 2650);
WIRE 16 -1 (-7500 2750)(-7500 2650);
WIRE 16 -1 (-6950 2650)(-6950 3000);
WIRE 16 -1 (-6075 3000)(-6950 3000);
FORCEPROP 2 LAST SIG_NAME P1V8_RETIMER_CPU1_VCC
J 0
(-6735 3025);
DISPLAY 0.489362 (-6735 3025);
PAINT SKYBLUE (-6735 3025);
FORCEPROP 2 LASTPROP $XRERR UNIQUE?
J 0
(-6975 3025);
DISPLAY 0.638298 (-6975 3025);
PAINT MONO (-6975 3025);
DISPLAY INVISIBLE (-6975 3025);
WIRE 16 -1 (-8500 3450)(-6075 3450);
FORCEPROP 2 LAST SIG_NAME P1V8_RETIMER_CPU1_EN
J 0
(-8160 3485);
DISPLAY 0.489362 (-8160 3485);
PAINT SKYBLUE (-8160 3485);
WIRE 16 -1 (-8500 3450)(-8500 3350);
WIRE 16 -1 (-8500 3450)(-8725 3450);
DOT 1 (-6700 4225);
DOT 1 (-6900 4225);
DOT 1 (-6700 3778);
DOT 1 (-6525 4225);
DOT 1 (-1625 3450);
DOT 1 (-750 3450);
DOT 1 (-1625 2950);
DOT 1 (-8500 3450);
DOT 1 (-9150 4225);
DOT 1 (-7500 2650);
DOT 1 (-5050 2600);
DOT 1 (-4625 3950);
DOT 1 (-4075 3000);
DOT 1 (-3800 3000);
DOT 1 (-3175 3000);
DOT 1 (-3925 3450);
DOT 1 (-2425 2950);
DOT 1 (-2150 2950);
DOT 1 (-2850 3450);
DOT 1 (-2775 3950);
DOT 1 (-2425 3450);
DOT 1 (-2150 3450);
DOT 1 (-1900 2950);
DOT 1 (-1350 2950);
DOT 1 (-1900 3450);
DOT 1 (-1350 3450);
DOT 1 (-1050 3450);
DOT 1 (-1025 2950);
DOT 1 (-1050 2950);
DOT 1 (-425 3450);
DOT 1 (-8400 4225);
DOT 1 (-7850 4225);
DOT 1 (-7675 4225);
DOT 1 (-7450 3778);
DOT 1 (-7450 4225);
DOT 1 (-7250 4225);
DOT 1 (-8400 3775);
DOT 1 (-8075 3778);
DOT 1 (-7875 3778);
DOT 1 (-6250 3950);
DOT 1 (-7250 3778);
DOT 1 (-6900 3778);
DOT 1 (-8075 4225);
DOT 1 (-7675 3778);
DOT 1 (-8525 4225);
DOT 1 (-7850 3778);
FORCENOTE
P1V8_CPU1_RT_1D
(-6925 5450) 0;
DISPLAY LEFT (-6925 5450);
DISPLAY 3.148936 (-6925 5450);
PAINT WHITE (-6925 5450);
FORCENOTE
2ND=CV-10^0MZ03
(-3700 3175) 0;
DISPLAY LEFT (-3700 3175);
DISPLAY 0.638298 (-3700 3175);
PAINT WHITE (-3700 3175);
FORCENOTE
RB
(-4200 2450) 0;
DISPLAY LEFT (-4200 2450);
DISPLAY 1.021277 (-4200 2450);
PAINT WHITE (-4200 2450);
FORCENOTE
ISAT:47A@100C
(-3700 3325) 0;
DISPLAY LEFT (-3700 3325);
DISPLAY 0.638298 (-3700 3325);
PAINT WHITE (-3700 3325);
FORCENOTE
FCCM
(-8650 2825) 0;
DISPLAY LEFT (-8650 2825);
DISPLAY 1.276596 (-8650 2825);
PAINT WHITE (-8650 2825);
FORCENOTE
PG2289.101HLT
(-8650 4525) 0;
DISPLAY LEFT (-8650 4525);
DISPLAY 0.638298 (-8650 4525);
PAINT WHITE (-8650 4525);
FORCENOTE
BOM CHANGE R&C TABLE
(-9025 1075) 0;
DISPLAY LEFT (-9025 1075);
DISPLAY 1.276596 (-9025 1075);
PAINT WHITE (-9025 1075);
FORCENOTE
FSW=600KHZ
(-8650 2725) 0;
DISPLAY LEFT (-8650 2725);
DISPLAY 1.276596 (-8650 2725);
PAINT WHITE (-8650 2725);
FORCENOTE
VOUT=0.6(1+RA/RB)=1.8V
(-4600 1925) 0;
DISPLAY LEFT (-4600 1925);
DISPLAY 2.000000 (-4600 1925);
PAINT WHITE (-4600 1925);
FORCENOTE
DCR=2.5M OHM
(-3700 3225) 0;
DISPLAY LEFT (-3700 3225);
DISPLAY 0.638298 (-3700 3225);
PAINT WHITE (-3700 3225);
FORCENOTE
13*13*5.0
(-3700 3275) 0;
DISPLAY LEFT (-3700 3275);
DISPLAY 0.638298 (-3700 3275);
PAINT WHITE (-3700 3275);
FORCENOTE
RA
(-3550 3100) 0;
DISPLAY LEFT (-3550 3100);
DISPLAY 1.021277 (-3550 3100);
PAINT WHITE (-3550 3100);
FORCENOTE
PCMC135T-1R0MF
(-3700 3375) 0;
DISPLAY LEFT (-3700 3375);
DISPLAY 0.638298 (-3700 3375);
PAINT WHITE (-3700 3375);
FORCENOTE
5.0*5.8
(-1475 2850) 0;
DISPLAY LEFT (-1475 2850);
DISPLAY 0.510638 (-1475 2850);
FORCENOTE
2ND=CC7390JMZ11
(-1475 2800) 0;
DISPLAY LEFT (-1475 2800);
DISPLAY 0.510638 (-1475 2800);
PAINT WHITE (-1475 2800);
FORCENOTE
ESR=10M OHM
(-1475 2900) 0;
DISPLAY LEFT (-1475 2900);
DISPLAY 0.510638 (-1475 2900);
FORCENOTE
ISAT:13A@100C
(-8650 4475) 0;
DISPLAY LEFT (-8650 4475);
DISPLAY 0.638298 (-8650 4475);
PAINT WHITE (-8650 4475);
FORCENOTE
4.5*4.7*4.5
(-8650 4425) 0;
DISPLAY LEFT (-8650 4425);
DISPLAY 0.638298 (-8650 4425);
PAINT WHITE (-8650 4425);
FORCENOTE
DCR:0.105M OHM
(-8650 4375) 0;
DISPLAY LEFT (-8650 4375);
DISPLAY 0.638298 (-8650 4375);
PAINT WHITE (-8650 4375);
FORCENOTE
2ND=CV+10G0MZ12
(-8650 4325) 0;
DISPLAY LEFT (-8650 4325);
DISPLAY 0.638298 (-8650 4325);
PAINT WHITE (-8650 4325);
FORCENOTE
3RD=CV+10G0MZ08
(-8650 4275) 0;
DISPLAY LEFT (-8650 4275);
DISPLAY 0.638298 (-8650 4275);
PAINT WHITE (-8650 4275);
FORCENOTE
OUTPUT VOLTAGE=1.8V +/- 5%
(-1825 6250) 0;
DISPLAY LEFT (-1825 6250);
DISPLAY 0.936170 (-1825 6250);
PAINT WHITE (-1825 6250);
FORCENOTE
AC + DC =1.710-1.890
(-1825 6175) 0;
DISPLAY LEFT (-1825 6175);
DISPLAY 0.936170 (-1825 6175);
PAINT WHITE (-1825 6175);
FORCENOTE
IOUT TDC=14.6A
(-1825 6100) 0;
DISPLAY LEFT (-1825 6100);
DISPLAY 0.936170 (-1825 6100);
PAINT WHITE (-1825 6100);
FORCENOTE
OCP=17.52A (IOUT MAX*1.2)
(-1825 5950) 0;
DISPLAY LEFT (-1825 5950);
DISPLAY 0.936170 (-1825 5950);
PAINT WHITE (-1825 5950);
FORCENOTE
WORK FREQUENCY=600KHZ
(-1825 5725) 0;
DISPLAY LEFT (-1825 5725);
DISPLAY 0.936170 (-1825 5725);
PAINT WHITE (-1825 5725);
FORCENOTE
SLEW RATE=1A/US
(-1825 5800) 0;
DISPLAY LEFT (-1825 5800);
DISPLAY 0.936170 (-1825 5800);
PAINT WHITE (-1825 5800);
FORCENOTE
EFFICIENCY > 90% @TDC
(-1825 5650) 0;
DISPLAY LEFT (-1825 5650);
DISPLAY 0.936170 (-1825 5650);
PAINT WHITE (-1825 5650);
FORCENOTE
LOAD STEP=7.2A
(-1825 5875) 0;
DISPLAY LEFT (-1825 5875);
DISPLAY 0.936170 (-1825 5875);
PAINT WHITE (-1825 5875);
FORCENOTE
IOUT MAX=15.72A
(-1825 6025) 0;
DISPLAY LEFT (-1825 6025);
DISPLAY 0.936170 (-1825 6025);
PAINT WHITE (-1825 6025);
FORCENOTE
SPECFICATION
(-1825 6375) 0;
DISPLAY LEFT (-1825 6375);
DISPLAY 1.276596 (-1825 6375);
PAINT WHITE (-1825 6375);
FORCENOTE
2ND AL053319002 / RS53319LR / REEDSEMI
(-9025 1425) 0;
DISPLAY LEFT (-9025 1425);
DISPLAY 1.021277 (-9025 1425);
FORCENOTE
1ST AL008633005 / MPQ8633BGLE-C838-Z/ MPS
(-9025 1525) 0;
DISPLAY LEFT (-9025 1525);
DISPLAY 1.021277 (-9025 1525);
FORCENOTE
BOM NOTE
(-9025 1625) 0;
DISPLAY LEFT (-9025 1625);
DISPLAY 1.276596 (-9025 1625);
PAINT WHITE (-9025 1625);
QUIT
